FILE_TYPE = MACRO_DRAWING;
SET COLOR_WIRE YELLOW;
SET COLOR_PROP ORANGE;
SET COLOR_DOT WHITE;
SET COLOR_ARC YELLOW;
SET COLOR_BODY GREEN;
SET COLOR_NOTE PURPLE;
SET PROP_DISPLAY VALUE;
SET PAGE_NUMBER P268;
FORCEADD UNIVERSAL_GND..1
(-8225 8375);
FORCEPROP 3 LASTPIN (-8225 8425) SIG_NAME GND\g
J 0
(-8215 8435);
DISPLAY 0.659574 (-8215 8435);
PAINT MONO (-8215 8435);
DISPLAY INVISIBLE (-8215 8435);
FORCEPROP 2 LAST CDS_LIB logical_power
J 0
(-8225 8375);
DISPLAY INVISIBLE (-8225 8375);
FORCEPROP 1 LAST HDL_POWER GND
J 1
(-8200 8300);
DISPLAY 0.702128 (-8200 8300);
PAINT GREEN (-8200 8300);
DISPLAY INVISIBLE (-8200 8300);
FORCEPROP 1 LAST PATH I1
J 0
(-8150 8375);
DISPLAY 0.872340 (-8150 8375);
PAINT AQUA (-8150 8375);
DISPLAY INVISIBLE (-8150 8375);
FORCEADD Q_RES..2
(-8225 9350);
FORCEPROP 1 LAST PART_NUMBER CS00002JB13
J 0
(-8185 9225);
DISPLAY 0.617021 (-8185 9225);
PAINT BLUE (-8185 9225);
DISPLAY INVISIBLE (-8185 9225);
FORCEPROP 1 LAST PACK_TYPE 0402LF
J 0
(-8185 9175);
DISPLAY 0.617021 (-8185 9175);
PAINT SKYBLUE (-8185 9175);
FORCEPROP 1 LAST TOLERANCE 5%
J 0
(-8180 9375);
DISPLAY 0.617021 (-8180 9375);
PAINT SKYBLUE (-8180 9375);
FORCEPROP 1 LAST VALUE 0
J 0
(-8180 9425);
DISPLAY 0.617021 (-8180 9425);
PAINT SKYBLUE (-8180 9425);
FORCEPROP 1 LAST MATERIAL CHIP
J 0
(-8185 9275);
DISPLAY 0.617021 (-8185 9275);
PAINT SKYBLUE (-8185 9275);
FORCEPROP 1 LAST WATTAGE 1/16W
J 0
(-8185 9325);
DISPLAY 0.617021 (-8185 9325);
PAINT SKYBLUE (-8185 9325);
FORCEPROP 1 LAST LOCATION PR3339
J 0
(-8180 9475);
DISPLAY 0.617021 (-8180 9475);
PAINT AQUA (-8180 9475);
FORCEPROP 1 LASTPIN (-8225 9450) $PN 1
J 0
(-8220 9412);
DISPLAY 0.787234 (-8220 9412);
PAINT MONO (-8220 9412);
FORCEPROP 1 LASTPIN (-8225 9250) $PN 2
J 0
(-8220 9260);
DISPLAY 0.787234 (-8220 9260);
PAINT MONO (-8220 9260);
FORCEPROP 2 LAST CDS_LIB pure_quanta
J 0
(-8225 9350);
DISPLAY INVISIBLE (-8225 9350);
FORCEPROP 1 LAST PATH I10
J 0
(-8175 9525);
DISPLAY 0.978723 (-8175 9525);
PAINT WHITE (-8175 9525);
DISPLAY INVISIBLE (-8175 9525);
FORCEPROP 0 LAST $SEC 1
J 0
(-8175 9525);
DISPLAY 0.680851 (-8175 9525);
PAINT MONO (-8175 9525);
DISPLAY INVISIBLE (-8175 9525);
FORCEPROP 0 LAST CDS_SEC 1
J 0
(-8175 9525);
DISPLAY 1.021277 (-8175 9525);
DISPLAY INVISIBLE (-8175 9525);
FORCEADD Q_RES..2
(-9125 9675);
FORCEPROP 1 LAST PART_NUMBER CS22002FB07
J 0
(-9085 9550);
DISPLAY 0.617021 (-9085 9550);
PAINT BLUE (-9085 9550);
DISPLAY INVISIBLE (-9085 9550);
FORCEPROP 1 LAST PACK_TYPE 0402LF
J 0
(-9085 9500);
DISPLAY 0.617021 (-9085 9500);
PAINT SKYBLUE (-9085 9500);
FORCEPROP 1 LAST MATERIAL CHIP
J 0
(-9085 9600);
DISPLAY 0.617021 (-9085 9600);
PAINT SKYBLUE (-9085 9600);
FORCEPROP 1 LAST WATTAGE 1/16W
J 0
(-9085 9650);
DISPLAY 0.617021 (-9085 9650);
PAINT SKYBLUE (-9085 9650);
FORCEPROP 1 LAST TOLERANCE 1%
J 0
(-9080 9700);
DISPLAY 0.617021 (-9080 9700);
PAINT SKYBLUE (-9080 9700);
FORCEPROP 1 LAST VALUE 2K
J 0
(-9080 9750);
DISPLAY 0.617021 (-9080 9750);
PAINT SKYBLUE (-9080 9750);
FORCEPROP 1 LAST LOCATION R1445
J 0
(-9080 9800);
DISPLAY 0.723404 (-9080 9800);
PAINT AQUA (-9080 9800);
FORCEPROP 1 LASTPIN (-9125 9775) $PN 1
J 0
(-9120 9737);
DISPLAY 0.617021 (-9120 9737);
FORCEPROP 1 LASTPIN (-9125 9575) $PN 2
J 0
(-9120 9585);
DISPLAY 0.617021 (-9120 9585);
FORCEPROP 2 LAST CDS_LIB pure_quanta
J 0
(-9125 9675);
PAINT MONO (-9125 9675);
DISPLAY INVISIBLE (-9125 9675);
FORCEPROP 1 LAST PATH I11
J 0
(-9075 9850);
DISPLAY 0.978723 (-9075 9850);
PAINT WHITE (-9075 9850);
DISPLAY INVISIBLE (-9075 9850);
FORCEPROP 2 LAST $SEC 1
J 0
(-9075 9900);
DISPLAY 0.680851 (-9075 9900);
PAINT MONO (-9075 9900);
DISPLAY INVISIBLE (-9075 9900);
FORCEPROP 2 LAST CDS_SEC 1
J 0
(-9075 9900);
DISPLAY 1.021277 (-9075 9900);
DISPLAY INVISIBLE (-9075 9900);
FORCEADD UNIVERSAL_GND..1
(-8800 10225);
FORCEPROP 3 LASTPIN (-8800 10275) SIG_NAME GND\g
J 0
(-8790 10285);
DISPLAY 0.659574 (-8790 10285);
PAINT MONO (-8790 10285);
DISPLAY INVISIBLE (-8790 10285);
FORCEPROP 2 LAST CDS_LIB logical_power
J 0
(-8800 10225);
PAINT MONO (-8800 10225);
DISPLAY INVISIBLE (-8800 10225);
FORCEPROP 1 LAST HDL_POWER GND
J 1
(-8775 10150);
DISPLAY 0.872340 (-8775 10150);
PAINT GREEN (-8775 10150);
DISPLAY INVISIBLE (-8775 10150);
FORCEPROP 1 LAST PATH I12
J 0
(-8725 10225);
DISPLAY 0.872340 (-8725 10225);
PAINT AQUA (-8725 10225);
DISPLAY INVISIBLE (-8725 10225);
FORCEADD Q_CAP..1
(-8800 10575);
FORCEPROP 1 LAST PART_NUMBER CH6223MEA01
J 0
(-8750 10375);
DISPLAY 0.617021 (-8750 10375);
PAINT BLUE (-8750 10375);
DISPLAY INVISIBLE (-8750 10375);
FORCEPROP 1 LAST TOLERANCE 20%
J 0
(-8750 10525);
DISPLAY 0.617021 (-8750 10525);
PAINT SKYBLUE (-8750 10525);
FORCEPROP 1 LAST MATERIAL X6S
J 0
(-8750 10475);
DISPLAY 0.617021 (-8750 10475);
PAINT SKYBLUE (-8750 10475);
FORCEPROP 1 LAST VALUE 22UF
J 0
(-8750 10625);
DISPLAY 0.617021 (-8750 10625);
PAINT SKYBLUE (-8750 10625);
FORCEPROP 1 LAST VOLTAGE 16V
J 0
(-8750 10575);
DISPLAY 0.617021 (-8750 10575);
PAINT SKYBLUE (-8750 10575);
FORCEPROP 1 LAST PACK_TYPE C0805
J 0
(-8750 10425);
DISPLAY 0.617021 (-8750 10425);
PAINT SKYBLUE (-8750 10425);
FORCEPROP 1 LAST LOCATION PC1272
J 0
(-8750 10675);
DISPLAY 0.617021 (-8750 10675);
PAINT AQUA (-8750 10675);
FORCEPROP 1 LASTPIN (-8800 10675) $PN 1
J 0
(-8790 10655);
DISPLAY 0.617021 (-8790 10655);
PAINT MONO (-8790 10655);
FORCEPROP 1 LASTPIN (-8800 10475) $PN 2
J 0
(-8790 10455);
DISPLAY 0.617021 (-8790 10455);
PAINT MONO (-8790 10455);
FORCEPROP 2 LAST CDS_LIB pure_quanta
J 0
(-8800 10575);
DISPLAY INVISIBLE (-8800 10575);
FORCEPROP 2 LAST BOM_COST VR_PCH
J 0
(-8750 10725);
DISPLAY 0.680851 (-8750 10725);
DISPLAY INVISIBLE (-8750 10725);
FORCEPROP 1 LAST PATH I13
J 0
(-8750 10725);
DISPLAY 0.978723 (-8750 10725);
PAINT WHITE (-8750 10725);
DISPLAY INVISIBLE (-8750 10725);
FORCEPROP 2 LAST $SEC 1
J 0
(-8750 10775);
DISPLAY 0.680851 (-8750 10775);
PAINT MONO (-8750 10775);
DISPLAY INVISIBLE (-8750 10775);
FORCEPROP 2 LAST CDS_SEC 1
J 0
(-8750 10775);
DISPLAY 1.021277 (-8750 10775);
DISPLAY INVISIBLE (-8750 10775);
FORCEADD VCCAUX15..1
(-8225 9550);
FORCEPROP 3 LASTPIN (-8225 9500) SIG_NAME P3V3_AUX\g
J 0
(-8215 9510);
DISPLAY 0.659574 (-8215 9510);
PAINT MONO (-8215 9510);
DISPLAY INVISIBLE (-8215 9510);
FORCEPROP 1 LAST HDL_POWER P3V3_AUX
J 1
(-8225 9592);
DISPLAY 0.617021 (-8225 9592);
PAINT GREEN (-8225 9592);
FORCEPROP 2 LAST BOM_COST VR_PCH
J 0
(-8225 9625);
DISPLAY 0.680851 (-8225 9625);
DISPLAY INVISIBLE (-8225 9625);
FORCEPROP 2 LAST CDS_LIB logical_power
J 0
(-8225 9550);
DISPLAY INVISIBLE (-8225 9550);
FORCEPROP 1 LAST PATH I14
J 0
(-8175 9575);
DISPLAY 0.872340 (-8175 9575);
PAINT AQUA (-8175 9575);
DISPLAY INVISIBLE (-8175 9575);
FORCEADD Q_CAP..1
(-8350 10575);
FORCEPROP 1 LAST PART_NUMBER CH6223MEA01
J 0
(-8300 10375);
DISPLAY 0.617021 (-8300 10375);
PAINT BLUE (-8300 10375);
DISPLAY INVISIBLE (-8300 10375);
FORCEPROP 1 LAST MATERIAL X6S
J 0
(-8300 10475);
DISPLAY 0.617021 (-8300 10475);
PAINT SKYBLUE (-8300 10475);
FORCEPROP 1 LAST VOLTAGE 16V
J 0
(-8300 10575);
DISPLAY 0.617021 (-8300 10575);
PAINT SKYBLUE (-8300 10575);
FORCEPROP 1 LAST VALUE 22UF
J 0
(-8300 10625);
DISPLAY 0.617021 (-8300 10625);
PAINT SKYBLUE (-8300 10625);
FORCEPROP 1 LAST TOLERANCE 20%
J 0
(-8300 10525);
DISPLAY 0.617021 (-8300 10525);
PAINT SKYBLUE (-8300 10525);
FORCEPROP 1 LAST PACK_TYPE C0805
J 0
(-8300 10425);
DISPLAY 0.617021 (-8300 10425);
PAINT SKYBLUE (-8300 10425);
FORCEPROP 1 LAST LOCATION PC1273
J 0
(-8300 10675);
DISPLAY 0.617021 (-8300 10675);
PAINT AQUA (-8300 10675);
FORCEPROP 1 LASTPIN (-8350 10675) $PN 1
J 0
(-8340 10655);
DISPLAY 0.617021 (-8340 10655);
PAINT MONO (-8340 10655);
FORCEPROP 1 LASTPIN (-8350 10475) $PN 2
J 0
(-8340 10455);
DISPLAY 0.617021 (-8340 10455);
PAINT MONO (-8340 10455);
FORCEPROP 2 LAST CDS_LIB pure_quanta
J 0
(-8350 10575);
DISPLAY INVISIBLE (-8350 10575);
FORCEPROP 2 LAST BOM_COST VR_PCH
J 0
(-8300 10725);
DISPLAY 0.680851 (-8300 10725);
DISPLAY INVISIBLE (-8300 10725);
FORCEPROP 1 LAST PATH I15
J 0
(-8300 10725);
DISPLAY 0.978723 (-8300 10725);
PAINT WHITE (-8300 10725);
DISPLAY INVISIBLE (-8300 10725);
FORCEPROP 2 LAST $SEC 1
J 0
(-8300 10775);
DISPLAY 0.680851 (-8300 10775);
PAINT MONO (-8300 10775);
DISPLAY INVISIBLE (-8300 10775);
FORCEPROP 2 LAST CDS_SEC 1
J 0
(-8300 10775);
DISPLAY 1.021277 (-8300 10775);
DISPLAY INVISIBLE (-8300 10775);
FORCEADD VCCAUX15..1
(-9125 11100);
FORCEPROP 3 LASTPIN (-9125 11050) SIG_NAME SW_P12V_PVCCINFAON_CPU0_FLT\g
J 0
(-9115 11060);
DISPLAY 0.659574 (-9115 11060);
PAINT MONO (-9115 11060);
DISPLAY INVISIBLE (-9115 11060);
FORCEPROP 1 LAST HDL_POWER SW_P12V_PVCCINFAON_CPU0_FLT
J 1
(-9125 11142);
DISPLAY 0.617021 (-9125 11142);
PAINT GREEN (-9125 11142);
FORCEPROP 2 LAST CDS_LIB logical_power
J 0
(-9125 11100);
DISPLAY INVISIBLE (-9125 11100);
FORCEPROP 2 LAST BOM_COST VR_PCH
J 0
(-9125 11175);
DISPLAY 0.680851 (-9125 11175);
DISPLAY INVISIBLE (-9125 11175);
FORCEPROP 1 LAST PATH I16
J 0
(-9075 11125);
DISPLAY 0.872340 (-9075 11125);
PAINT AQUA (-9075 11125);
DISPLAY INVISIBLE (-9075 11125);
FORCEADD UNIVERSAL_GND..1
(-7825 8375);
FORCEPROP 3 LASTPIN (-7825 8425) SIG_NAME GND\g
J 0
(-7815 8435);
DISPLAY 0.659574 (-7815 8435);
PAINT MONO (-7815 8435);
DISPLAY INVISIBLE (-7815 8435);
FORCEPROP 2 LAST CDS_LIB logical_power
J 0
(-7825 8375);
DISPLAY INVISIBLE (-7825 8375);
FORCEPROP 1 LAST HDL_POWER GND
J 1
(-7800 8300);
DISPLAY 0.702128 (-7800 8300);
PAINT GREEN (-7800 8300);
DISPLAY INVISIBLE (-7800 8300);
FORCEPROP 1 LAST PATH I17
J 0
(-7750 8375);
DISPLAY 0.872340 (-7750 8375);
PAINT AQUA (-7750 8375);
DISPLAY INVISIBLE (-7750 8375);
FORCEADD UNIVERSAL_GND..1
(-6450 8250);
FORCEPROP 3 LASTPIN (-6450 8300) SIG_NAME GND\g
J 0
(-6440 8310);
DISPLAY 0.659574 (-6440 8310);
PAINT MONO (-6440 8310);
DISPLAY INVISIBLE (-6440 8310);
FORCEPROP 2 LAST CDS_LIB logical_power
J 0
(-6450 8250);
DISPLAY INVISIBLE (-6450 8250);
FORCEPROP 1 LAST HDL_POWER GND
J 1
(-6425 8175);
DISPLAY 0.702128 (-6425 8175);
PAINT GREEN (-6425 8175);
DISPLAY INVISIBLE (-6425 8175);
FORCEPROP 1 LAST PATH I18
J 0
(-6375 8250);
DISPLAY 0.872340 (-6375 8250);
PAINT AQUA (-6375 8250);
DISPLAY INVISIBLE (-6375 8250);
FORCEADD Q_RES..1
(-5275 8375);
FORCEPROP 1 LAST PART_NUMBER CS00002JB13
J 0
(-5425 8300);
DISPLAY 0.638298 (-5425 8300);
DISPLAY INVISIBLE (-5425 8300);
FORCEPROP 1 LAST TOLERANCE 5%
J 0
(-5000 8375);
DISPLAY 0.510638 (-5000 8375);
FORCEPROP 1 LAST VALUE 0
J 2
(-5050 8375);
DISPLAY 0.510638 (-5050 8375);
FORCEPROP 1 LAST MATERIAL CHIP
J 0
(-4925 8375);
DISPLAY 0.510638 (-4925 8375);
FORCEPROP 1 LAST PACK_TYPE 0402LF
J 0
(-5200 8250);
DISPLAY 0.638298 (-5200 8250);
FORCEPROP 1 LAST WATTAGE 1/16W
J 2
(-5275 8250);
DISPLAY 0.638298 (-5275 8250);
FORCEPROP 1 LAST LOCATION PR1
J 0
(-5550 8375);
DISPLAY 0.638298 (-5550 8375);
FORCEPROP 1 LASTPIN (-5375 8375) $PN 1
J 0
(-5363 8387);
DISPLAY 0.787234 (-5363 8387);
PAINT MONO (-5363 8387);
FORCEPROP 1 LASTPIN (-5175 8375) $PN 2
J 0
(-5213 8387);
DISPLAY 0.787234 (-5213 8387);
PAINT MONO (-5213 8387);
FORCEPROP 1 LAST PATH I19
J 0
(-5325 8525);
DISPLAY 0.978723 (-5325 8525);
PAINT WHITE (-5325 8525);
DISPLAY INVISIBLE (-5325 8525);
FORCEPROP 2 LAST CDS_LIB pure_quanta
J 0
(-5275 8375);
PAINT MONO (-5275 8375);
DISPLAY INVISIBLE (-5275 8375);
FORCEPROP 0 LAST $SEC 1
J 0
(-5325 8525);
DISPLAY 0.680851 (-5325 8525);
PAINT MONO (-5325 8525);
DISPLAY INVISIBLE (-5325 8525);
FORCEPROP 2 LAST CDS_SEC 1
J 0
(-5325 8575);
DISPLAY 1.021277 (-5325 8575);
DISPLAY INVISIBLE (-5325 8575);
FORCEADD OFFPAGE..4
R 2
(-10150 9850);
FORCEPROP 2 LASTPIN (-10100 9850) SIG_NAME FM_PVNN_MAIN_CPU0_EN
J 0
(-8060 9860);
DISPLAY 0.617021 (-8060 9860);
FORCEPROP 2 LAST $XR0 214 
J 0
(-10402 9850);
DISPLAY 0.638298 (-10402 9850);
PAINT MONO (-10402 9850);
FORCEPROP 2 LAST CDS_LIB standard
J 0
(-10150 9850);
DISPLAY INVISIBLE (-10150 9850);
FORCEPROP 1 LAST OFFPAGE TRUE
J 2
(-10475 9725);
DISPLAY 0.872340 (-10475 9725);
PAINT GREEN (-10475 9725);
DISPLAY INVISIBLE (-10475 9725);
FORCEPROP 1 LAST COMMENT_BODY TRUE
J 2
(-10125 9750);
DISPLAY 0.872340 (-10125 9750);
PAINT GREEN (-10125 9750);
DISPLAY INVISIBLE (-10125 9750);
FORCEPROP 2 LAST PATH I2
J 0
(-10400 9900);
DISPLAY 1.021277 (-10400 9900);
DISPLAY INVISIBLE (-10400 9900);
FORCEADD UNIVERSAL_GND..1
(-1550 8025);
FORCEPROP 3 LASTPIN (-1550 8075) SIG_NAME GND\g
J 0
(-1540 8085);
DISPLAY 0.659574 (-1540 8085);
PAINT MONO (-1540 8085);
DISPLAY INVISIBLE (-1540 8085);
FORCEPROP 1 LAST HDL_POWER GND
J 1
(-1525 7950);
DISPLAY 0.702128 (-1525 7950);
PAINT GREEN (-1525 7950);
DISPLAY INVISIBLE (-1525 7950);
FORCEPROP 2 LAST CDS_LIB logical_power
J 0
(-1550 8025);
DISPLAY INVISIBLE (-1550 8025);
FORCEPROP 1 LAST PATH I20
J 0
(-1475 8025);
DISPLAY 0.872340 (-1475 8025);
PAINT AQUA (-1475 8025);
DISPLAY INVISIBLE (-1475 8025);
FORCEADD Q_RES..2
(-7825 8675);
FORCEPROP 1 LAST PART_NUMBER CS32262FB02
J 0
(-7785 8550);
DISPLAY 0.617021 (-7785 8550);
PAINT BLUE (-7785 8550);
DISPLAY INVISIBLE (-7785 8550);
FORCEPROP 1 LAST PACK_TYPE 0402LF
J 0
(-7785 8500);
DISPLAY 0.617021 (-7785 8500);
PAINT SKYBLUE (-7785 8500);
FORCEPROP 1 LAST MATERIAL CHIP
J 0
(-7785 8600);
DISPLAY 0.617021 (-7785 8600);
PAINT SKYBLUE (-7785 8600);
FORCEPROP 1 LAST WATTAGE 1/16W
J 0
(-7785 8650);
DISPLAY 0.617021 (-7785 8650);
PAINT SKYBLUE (-7785 8650);
FORCEPROP 1 LAST TOLERANCE 1%
J 0
(-7780 8700);
DISPLAY 0.617021 (-7780 8700);
PAINT SKYBLUE (-7780 8700);
FORCEPROP 1 LAST VALUE 22.6K
J 0
(-7780 8750);
DISPLAY 0.617021 (-7780 8750);
PAINT SKYBLUE (-7780 8750);
FORCEPROP 1 LAST LOCATION PR1303
J 0
(-7780 8800);
DISPLAY 0.617021 (-7780 8800);
PAINT AQUA (-7780 8800);
FORCEPROP 1 LASTPIN (-7825 8775) $PN 1
J 0
(-7820 8737);
DISPLAY 0.617021 (-7820 8737);
PAINT MONO (-7820 8737);
FORCEPROP 1 LASTPIN (-7825 8575) $PN 2
J 0
(-7820 8585);
DISPLAY 0.617021 (-7820 8585);
PAINT MONO (-7820 8585);
FORCEPROP 2 LAST CDS_LIB pure_quanta
J 0
(-7825 8675);
DISPLAY INVISIBLE (-7825 8675);
FORCEPROP 1 LAST PATH I21
J 0
(-7775 8850);
DISPLAY 0.978723 (-7775 8850);
PAINT WHITE (-7775 8850);
DISPLAY INVISIBLE (-7775 8850);
FORCEPROP 0 LAST $SEC 1
J 0
(-7775 8850);
DISPLAY 0.680851 (-7775 8850);
PAINT MONO (-7775 8850);
DISPLAY INVISIBLE (-7775 8850);
FORCEPROP 0 LAST CDS_SEC 1
J 0
(-7775 8850);
DISPLAY 1.021277 (-7775 8850);
DISPLAY INVISIBLE (-7775 8850);
FORCEADD RS53317LR..1
(-6900 9675);
FORCEPROP 1 LAST PART_NUMBER AL053317005
J 0
(-7147 10531);
DISPLAY 0.723404 (-7147 10531);
PAINT GREEN (-7147 10531);
DISPLAY INVISIBLE (-7147 10531);
FORCEPROP 2 LAST VALUE RS53317LR
J 0
(-7150 10575);
DISPLAY 0.617021 (-7150 10575);
PAINT SKYBLUE (-7150 10575);
FORCEPROP 2 LAST PART_TYPE SMLF
J 0
(-7150 10625);
DISPLAY 0.510638 (-7150 10625);
PAINT SKYBLUE (-7150 10625);
FORCEPROP 1 LAST MATERIAL IC
J 0
(-7147 10404);
DISPLAY 0.723404 (-7147 10404);
PAINT GREEN (-7147 10404);
FORCEPROP 1 LAST LOCATION PU81
J 0
(-7147 10678);
DISPLAY 0.723404 (-7147 10678);
PAINT GREEN (-7147 10678);
FORCEPROP 2 LASTPIN (-6500 9000) $PN 7
J 0
(-6490 9010);
DISPLAY 0.680851 (-6490 9010);
PAINT MONO (-6490 9010);
FORCEPROP 2 LASTPIN (-6500 10150) $PN 10
J 0
(-6490 10160);
DISPLAY 0.680851 (-6490 10160);
PAINT MONO (-6490 10160);
FORCEPROP 2 LASTPIN (-7300 9050) $PN 4
J 2
(-7310 9060);
DISPLAY 0.680851 (-7310 9060);
PAINT MONO (-7310 9060);
FORCEPROP 2 LASTPIN (-7300 9850) $PN 5
J 2
(-7310 9860);
DISPLAY 0.680851 (-7310 9860);
PAINT MONO (-7310 9860);
FORCEPROP 2 LASTPIN (-6500 9400) $PN 6
J 0
(-6490 9410);
DISPLAY 0.680851 (-6490 9410);
PAINT MONO (-6490 9410);
FORCEPROP 2 LASTPIN (-7300 9650) $PN 12
J 2
(-7310 9660);
DISPLAY 0.680851 (-7310 9660);
PAINT MONO (-7310 9660);
FORCEPROP 2 LASTPIN (-6500 9250) $PN 1
J 0
(-6490 9260);
DISPLAY 0.680851 (-6490 9260);
PAINT MONO (-6490 9260);
FORCEPROP 2 LASTPIN (-6500 9050) $PN 14
J 0
(-6490 9060);
DISPLAY 0.680851 (-6490 9060);
PAINT MONO (-6490 9060);
FORCEPROP 2 LASTPIN (-6500 10350) $PN 9
J 0
(-6490 10360);
DISPLAY 0.680851 (-6490 10360);
PAINT MONO (-6490 10360);
FORCEPROP 2 LASTPIN (-6500 9150) $PN 8
J 0
(-6490 9160);
DISPLAY 0.680851 (-6490 9160);
PAINT MONO (-6490 9160);
FORCEPROP 2 LASTPIN (-6500 9900) $PN 2
J 0
(-6490 9910);
DISPLAY 0.680851 (-6490 9910);
PAINT MONO (-6490 9910);
FORCEPROP 2 LASTPIN (-6500 9850) $PN 11
J 0
(-6490 9860);
DISPLAY 0.680851 (-6490 9860);
PAINT MONO (-6490 9860);
FORCEPROP 2 LASTPIN (-7300 9400) $PN 13
J 2
(-7310 9410);
DISPLAY 0.680851 (-7310 9410);
PAINT MONO (-7310 9410);
FORCEPROP 2 LASTPIN (-7300 10350) $PN 3
J 2
(-7310 10360);
DISPLAY 0.680851 (-7310 10360);
PAINT MONO (-7310 10360);
FORCEPROP 2 LAST SEC_TYPE 
J 0
(-7125 10725);
DISPLAY 1.021277 (-7125 10725);
DISPLAY INVISIBLE (-7125 10725);
FORCEPROP 2 LAST CDS_LIB pure_quanta
J 0
(-6900 9675);
DISPLAY INVISIBLE (-6900 9675);
FORCEPROP 1 LAST NEEDS_NO_SIZE TRUE
J 0
(-6900 9675);
DISPLAY 0.723404 (-6900 9675);
PAINT GREEN (-6900 9675);
DISPLAY INVISIBLE (-6900 9675);
FORCEPROP 1 LAST CDS_LMAN_SYM_OUTLINE -250,725,250,-725
J 0
(-6900 9675);
DISPLAY 0.468085 (-6900 9675);
PAINT GREEN (-6900 9675);
DISPLAY INVISIBLE (-6900 9675);
FORCEPROP 1 LAST PATH I22
J 0
(-6900 9675);
DISPLAY 0.723404 (-6900 9675);
PAINT GREEN (-6900 9675);
DISPLAY INVISIBLE (-6900 9675);
FORCEPROP 2 LAST SEC 1
J 0
(-7125 10725);
DISPLAY 0.680851 (-7125 10725);
PAINT MONO (-7125 10725);
DISPLAY INVISIBLE (-7125 10725);
FORCEADD Q_CAP..1
(-7800 10575);
FORCEPROP 1 LAST PART_NUMBER CH5103KEB01
J 0
(-7750 10375);
DISPLAY 0.617021 (-7750 10375);
PAINT BLUE (-7750 10375);
DISPLAY INVISIBLE (-7750 10375);
FORCEPROP 1 LAST MATERIAL X6S
J 0
(-7750 10475);
DISPLAY 0.617021 (-7750 10475);
PAINT SKYBLUE (-7750 10475);
FORCEPROP 1 LAST VALUE 1UF
J 0
(-7750 10625);
DISPLAY 0.617021 (-7750 10625);
PAINT SKYBLUE (-7750 10625);
FORCEPROP 1 LAST VOLTAGE 16V
J 0
(-7750 10575);
DISPLAY 0.617021 (-7750 10575);
PAINT SKYBLUE (-7750 10575);
FORCEPROP 1 LAST TOLERANCE 10%
J 0
(-7750 10525);
DISPLAY 0.617021 (-7750 10525);
PAINT SKYBLUE (-7750 10525);
FORCEPROP 1 LAST PACK_TYPE C0402
J 0
(-7750 10425);
DISPLAY 0.617021 (-7750 10425);
PAINT SKYBLUE (-7750 10425);
FORCEPROP 1 LAST LOCATION PC1274
J 0
(-7750 10675);
DISPLAY 0.617021 (-7750 10675);
PAINT AQUA (-7750 10675);
FORCEPROP 1 LASTPIN (-7800 10675) $PN 1
J 0
(-7790 10655);
DISPLAY 0.617021 (-7790 10655);
FORCEPROP 1 LASTPIN (-7800 10475) $PN 2
J 0
(-7790 10455);
DISPLAY 0.617021 (-7790 10455);
FORCEPROP 2 LAST CDS_LIB pure_quanta
J 0
(-7800 10575);
PAINT MONO (-7800 10575);
DISPLAY INVISIBLE (-7800 10575);
FORCEPROP 1 LAST PATH I23
J 0
(-7750 10725);
DISPLAY 0.978723 (-7750 10725);
PAINT WHITE (-7750 10725);
DISPLAY INVISIBLE (-7750 10725);
FORCEPROP 1 LAST LOCATION PC1274
J 0
(-7750 10750);
DISPLAY 1.021277 (-7750 10750);
PAINT AQUA (-7750 10750);
DISPLAY INVISIBLE (-7750 10750);
FORCEPROP 2 LAST $SEC 1
J 0
(-7750 10775);
DISPLAY 0.680851 (-7750 10775);
PAINT MONO (-7750 10775);
DISPLAY INVISIBLE (-7750 10775);
FORCEPROP 2 LAST CDS_SEC 1
J 0
(-7750 10775);
DISPLAY 1.021277 (-7750 10775);
DISPLAY INVISIBLE (-7750 10775);
FORCEADD UNIVERSAL_GND..1
(-6300 8750);
FORCEPROP 3 LASTPIN (-6300 8800) SIG_NAME GND\g
J 0
(-6290 8810);
DISPLAY 0.659574 (-6290 8810);
PAINT MONO (-6290 8810);
DISPLAY INVISIBLE (-6290 8810);
FORCEPROP 2 LAST CDS_LIB logical_power
J 0
(-6300 8750);
DISPLAY INVISIBLE (-6300 8750);
FORCEPROP 1 LAST HDL_POWER GND
J 1
(-6275 8675);
DISPLAY 0.702128 (-6275 8675);
PAINT GREEN (-6275 8675);
DISPLAY INVISIBLE (-6275 8675);
FORCEPROP 1 LAST PATH I24
J 0
(-6225 8750);
DISPLAY 0.872340 (-6225 8750);
PAINT AQUA (-6225 8750);
DISPLAY INVISIBLE (-6225 8750);
FORCEADD Q_CAP..1
(-5825 8675);
FORCEPROP 1 LAST PART_NUMBER TMP_QCH2336K1B12
J 0
(-5775 8525);
DISPLAY 0.617021 (-5775 8525);
PAINT BLUE (-5775 8525);
DISPLAY INVISIBLE (-5775 8525);
FORCEPROP 1 LAST TOLERANCE 10%
J 0
(-5775 8625);
DISPLAY 0.617021 (-5775 8625);
PAINT SKYBLUE (-5775 8625);
FORCEPROP 1 LAST MATERIAL X7R
J 0
(-5775 8575);
DISPLAY 0.617021 (-5775 8575);
PAINT SKYBLUE (-5775 8575);
FORCEPROP 1 LAST VALUE 3300PF
J 0
(-5775 8725);
DISPLAY 0.617021 (-5775 8725);
PAINT SKYBLUE (-5775 8725);
FORCEPROP 1 LAST VOLTAGE 50V
J 0
(-5775 8675);
DISPLAY 0.617021 (-5775 8675);
PAINT SKYBLUE (-5775 8675);
FORCEPROP 1 LAST PACK_TYPE 0402
J 0
(-5775 8475);
DISPLAY 0.617021 (-5775 8475);
PAINT SKYBLUE (-5775 8475);
FORCEPROP 1 LAST LOCATION PC27
J 0
(-5775 8775);
DISPLAY 0.765957 (-5775 8775);
PAINT AQUA (-5775 8775);
FORCEPROP 2 LAST CDS_LIB pure_quanta
J 0
(-5825 8675);
DISPLAY INVISIBLE (-5825 8675);
FORCEPROP 1 LAST PATH I25
J 0
(-5775 8825);
DISPLAY 0.978723 (-5775 8825);
PAINT WHITE (-5775 8825);
DISPLAY INVISIBLE (-5775 8825);
FORCEPROP 0 LAST $SEC 1
J 0
(-5775 8825);
DISPLAY 0.680851 (-5775 8825);
PAINT MONO (-5775 8825);
DISPLAY INVISIBLE (-5775 8825);
FORCEPROP 0 LAST CDS_SEC 1
J 0
(-5775 8825);
DISPLAY 1.021277 (-5775 8825);
DISPLAY INVISIBLE (-5775 8825);
FORCEPROP 1 LASTPIN (-5825 8775) $PN 1
J 0
(-5815 8755);
DISPLAY 0.808511 (-5815 8755);
PAINT WHITE (-5815 8755);
DISPLAY INVISIBLE (-5815 8755);
FORCEPROP 1 LASTPIN (-5825 8575) $PN 2
J 0
(-5815 8555);
DISPLAY 0.808511 (-5815 8555);
PAINT WHITE (-5815 8555);
DISPLAY INVISIBLE (-5815 8555);
FORCEADD Q_CAP..1
(-5175 10000);
FORCEPROP 1 LAST PART_NUMBER CH4224K1B01
J 0
(-5075 9900);
DISPLAY 0.617021 (-5075 9900);
PAINT BLUE (-5075 9900);
DISPLAY INVISIBLE (-5075 9900);
FORCEPROP 1 LAST VALUE 0.22UF
J 0
(-5075 10100);
DISPLAY 0.617021 (-5075 10100);
PAINT SKYBLUE (-5075 10100);
FORCEPROP 1 LAST PACK_TYPE C0402
J 0
(-5075 9850);
DISPLAY 0.617021 (-5075 9850);
PAINT SKYBLUE (-5075 9850);
FORCEPROP 1 LAST VOLTAGE 25V
J 0
(-5075 10050);
DISPLAY 0.617021 (-5075 10050);
PAINT SKYBLUE (-5075 10050);
FORCEPROP 1 LAST TOLERANCE 10%
J 0
(-5075 10000);
DISPLAY 0.617021 (-5075 10000);
PAINT SKYBLUE (-5075 10000);
FORCEPROP 1 LAST MATERIAL X7R
J 0
(-5075 9950);
DISPLAY 0.617021 (-5075 9950);
PAINT SKYBLUE (-5075 9950);
FORCEPROP 1 LAST LOCATION PC1275
J 0
(-5075 10125);
DISPLAY 0.617021 (-5075 10125);
PAINT AQUA (-5075 10125);
FORCEPROP 1 LASTPIN (-5175 10100) $PN 1
J 0
(-5165 10080);
DISPLAY 0.787234 (-5165 10080);
PAINT MONO (-5165 10080);
FORCEPROP 1 LASTPIN (-5175 9900) $PN 2
J 0
(-5165 9880);
DISPLAY 0.787234 (-5165 9880);
PAINT MONO (-5165 9880);
FORCEPROP 2 LAST CDS_LIB pure_quanta
J 0
(-5175 10000);
DISPLAY INVISIBLE (-5175 10000);
FORCEPROP 1 LAST PATH I26
J 0
(-5125 10150);
DISPLAY 0.978723 (-5125 10150);
PAINT WHITE (-5125 10150);
DISPLAY INVISIBLE (-5125 10150);
FORCEPROP 0 LAST $SEC 1
J 0
(-5075 10175);
DISPLAY 0.680851 (-5075 10175);
PAINT MONO (-5075 10175);
DISPLAY INVISIBLE (-5075 10175);
FORCEPROP 0 LAST CDS_SEC 1
J 0
(-5075 10175);
DISPLAY 1.021277 (-5075 10175);
DISPLAY INVISIBLE (-5075 10175);
FORCEADD Q_RES..1
(-5450 10150);
FORCEPROP 1 LAST PART_NUMBER CS00002JB13
J 0
(-5600 10075);
DISPLAY 0.617021 (-5600 10075);
PAINT BLUE (-5600 10075);
DISPLAY INVISIBLE (-5600 10075);
FORCEPROP 1 LAST PACK_TYPE 0402LF
J 0
(-5425 10025);
DISPLAY 0.638298 (-5425 10025);
PAINT SKYBLUE (-5425 10025);
FORCEPROP 1 LAST MATERIAL CHIP
J 0
(-5600 10025);
DISPLAY 0.617021 (-5600 10025);
PAINT SKYBLUE (-5600 10025);
FORCEPROP 1 LAST VALUE 0
J 2
(-5425 10225);
DISPLAY 0.617021 (-5425 10225);
PAINT SKYBLUE (-5425 10225);
FORCEPROP 1 LAST TOLERANCE 5%
J 0
(-5400 10225);
DISPLAY 0.617021 (-5400 10225);
PAINT SKYBLUE (-5400 10225);
FORCEPROP 1 LAST LOCATION PR4271
J 0
(-5675 10150);
DISPLAY 0.638298 (-5675 10150);
PAINT AQUA (-5675 10150);
FORCEPROP 1 LASTPIN (-5550 10150) $PN 1
J 0
(-5538 10162);
DISPLAY 0.787234 (-5538 10162);
PAINT MONO (-5538 10162);
FORCEPROP 1 LASTPIN (-5350 10150) $PN 2
J 0
(-5388 10162);
DISPLAY 0.787234 (-5388 10162);
PAINT MONO (-5388 10162);
FORCEPROP 2 LAST CDS_LIB pure_quanta
J 0
(-5450 10150);
DISPLAY INVISIBLE (-5450 10150);
FORCEPROP 2 LAST SEC_TYPE 0402LF
J 0
(-5500 10350);
DISPLAY 1.021277 (-5500 10350);
DISPLAY INVISIBLE (-5500 10350);
FORCEPROP 1 LAST WATTAGE 1/16W
J 2
(-5275 10225);
DISPLAY 0.404255 (-5275 10225);
PAINT SKYBLUE (-5275 10225);
DISPLAY INVISIBLE (-5275 10225);
FORCEPROP 1 LAST PATH I27
J 0
(-5500 10300);
DISPLAY 0.978723 (-5500 10300);
PAINT WHITE (-5500 10300);
DISPLAY INVISIBLE (-5500 10300);
FORCEPROP 2 LAST SEC 1
J 0
(-5500 10350);
DISPLAY 0.680851 (-5500 10350);
PAINT MONO (-5500 10350);
DISPLAY INVISIBLE (-5500 10350);
FORCEADD Q_RES..2
(-4600 8675);
FORCEPROP 1 LAST PART_NUMBER CS31242BB10
J 0
(-4560 8521);
DISPLAY 0.617021 (-4560 8521);
PAINT BLUE (-4560 8521);
DISPLAY INVISIBLE (-4560 8521);
FORCEPROP 1 LAST PACK_TYPE 0402LF
J 0
(-4560 8471);
DISPLAY 0.617021 (-4560 8471);
PAINT SKYBLUE (-4560 8471);
FORCEPROP 1 LAST VALUE 12.4K
J 0
(-4555 8721);
DISPLAY 0.617021 (-4555 8721);
PAINT SKYBLUE (-4555 8721);
FORCEPROP 1 LAST TOLERANCE 0.1%
J 0
(-4555 8671);
DISPLAY 0.617021 (-4555 8671);
PAINT SKYBLUE (-4555 8671);
FORCEPROP 1 LAST MATERIAL CHIP
J 0
(-4560 8571);
DISPLAY 0.617021 (-4560 8571);
PAINT SKYBLUE (-4560 8571);
FORCEPROP 1 LAST WATTAGE 1/16W
J 0
(-4560 8621);
DISPLAY 0.617021 (-4560 8621);
PAINT SKYBLUE (-4560 8621);
FORCEPROP 1 LAST LOCATION PR50
J 0
(-4550 8775);
DISPLAY 0.765957 (-4550 8775);
PAINT AQUA (-4550 8775);
FORCEPROP 1 LASTPIN (-4600 8775) $PN 1
J 0
(-4595 8699);
DISPLAY 0.617021 (-4595 8699);
PAINT WHITE (-4595 8699);
FORCEPROP 1 LASTPIN (-4600 8575) $PN 2
J 0
(-4595 8547);
DISPLAY 0.617021 (-4595 8547);
PAINT WHITE (-4595 8547);
FORCEPROP 2 LAST CDS_LIB pure_quanta
J 0
(-4600 8628);
DISPLAY INVISIBLE (-4600 8628);
FORCEPROP 2 LAST SEC_TYPE 0402LF
J 0
(-4575 8352);
DISPLAY 1.021277 (-4575 8352);
DISPLAY INVISIBLE (-4575 8352);
FORCEPROP 1 LAST PATH I28
J 0
(-4550 8850);
DISPLAY 0.978723 (-4550 8850);
PAINT WHITE (-4550 8850);
DISPLAY INVISIBLE (-4550 8850);
FORCEPROP 0 LAST SEC 1
J 0
(-4550 8443);
DISPLAY 0.680851 (-4550 8443);
PAINT MONO (-4550 8443);
DISPLAY INVISIBLE (-4550 8443);
FORCEADD Q_INDUCTOR..1
(-4475 9875);
FORCEPROP 1 LAST PART_NUMBER CV-4755MZ12
J 0
(-4600 9985);
DISPLAY 0.617021 (-4600 9985);
PAINT BLUE (-4600 9985);
DISPLAY INVISIBLE (-4600 9985);
FORCEPROP 2 LAST VALUE 4.7UH
J 0
(-4600 10050);
DISPLAY 0.617021 (-4600 10050);
PAINT SKYBLUE (-4600 10050);
FORCEPROP 2 LAST PACK_TYPE SMLF
J 0
(-4600 10100);
DISPLAY 0.617021 (-4600 10100);
PAINT SKYBLUE (-4600 10100);
FORCEPROP 1 LAST MATERIAL IND
J 0
(-4600 9930);
DISPLAY 0.617021 (-4600 9930);
PAINT SKYBLUE (-4600 9930);
FORCEPROP 1 LAST LOCATION PL120
J 0
(-4725 9860);
DISPLAY 0.617021 (-4725 9860);
PAINT AQUA (-4725 9860);
FORCEPROP 2 LASTPIN (-4575 9850) $PN 1
J 2
(-4585 9860);
DISPLAY 0.617021 (-4585 9860);
FORCEPROP 2 LASTPIN (-4375 9850) $PN 2
J 0
(-4365 9860);
DISPLAY 0.617021 (-4365 9860);
FORCEPROP 2 LAST BOM_COST VR_PCH
J 0
(-4600 10175);
DISPLAY 0.680851 (-4600 10175);
DISPLAY INVISIBLE (-4600 10175);
FORCEPROP 2 LAST CDS_LIB pure_quanta
J 0
(-4475 9875);
PAINT MONO (-4475 9875);
DISPLAY INVISIBLE (-4475 9875);
FORCEPROP 1 LAST NEEDS_NO_SIZE TRUE
J 0
(-4475 9875);
DISPLAY 0.468085 (-4475 9875);
PAINT GREEN (-4475 9875);
DISPLAY INVISIBLE (-4475 9875);
FORCEPROP 1 LAST PATH I29
J 0
(-4400 9930);
DISPLAY 0.723404 (-4400 9930);
PAINT GREEN (-4400 9930);
DISPLAY INVISIBLE (-4400 9930);
FORCEPROP 2 LAST $SEC 1
J 0
(-4600 10150);
DISPLAY 0.680851 (-4600 10150);
PAINT MONO (-4600 10150);
DISPLAY INVISIBLE (-4600 10150);
FORCEPROP 2 LAST CDS_SEC 1
J 0
(-4600 10150);
DISPLAY 1.021277 (-4600 10150);
DISPLAY INVISIBLE (-4600 10150);
FORCEADD VCCAUX15..1
(-10350 10175);
FORCEPROP 3 LASTPIN (-10350 10125) SIG_NAME P3V3_AUX\g
J 0
(-10340 10135);
DISPLAY 0.659574 (-10340 10135);
PAINT MONO (-10340 10135);
DISPLAY INVISIBLE (-10340 10135);
FORCEPROP 1 LAST HDL_POWER P3V3_AUX
J 1
(-10325 10192);
DISPLAY 0.617021 (-10325 10192);
PAINT GREEN (-10325 10192);
FORCEPROP 2 LAST BOM_COST VR_PCH
J 0
(-10350 10250);
DISPLAY 0.680851 (-10350 10250);
DISPLAY INVISIBLE (-10350 10250);
FORCEPROP 2 LAST CDS_LIB logical_power
J 0
(-10350 10175);
PAINT MONO (-10350 10175);
DISPLAY INVISIBLE (-10350 10175);
FORCEPROP 1 LAST PATH I3
J 0
(-10300 10200);
DISPLAY 0.872340 (-10300 10200);
PAINT AQUA (-10300 10200);
DISPLAY INVISIBLE (-10300 10200);
FORCEADD UNIVERSAL_GND..1
(-4350 10225);
FORCEPROP 3 LASTPIN (-4350 10275) SIG_NAME GND\g
J 0
(-4340 10285);
DISPLAY 0.659574 (-4340 10285);
PAINT MONO (-4340 10285);
DISPLAY INVISIBLE (-4340 10285);
FORCEPROP 2 LAST CDS_LIB logical_power
J 0
(-4350 10225);
PAINT MONO (-4350 10225);
DISPLAY INVISIBLE (-4350 10225);
FORCEPROP 1 LAST HDL_POWER GND
J 1
(-4325 10150);
DISPLAY 0.872340 (-4325 10150);
PAINT GREEN (-4325 10150);
DISPLAY INVISIBLE (-4325 10150);
FORCEPROP 1 LAST PATH I30
J 0
(-4275 10225);
DISPLAY 0.872340 (-4275 10225);
PAINT AQUA (-4275 10225);
DISPLAY INVISIBLE (-4275 10225);
FORCEADD Q_CAP..1
(-4350 10450);
FORCEPROP 1 LAST PART_NUMBER TMP_QCH21006JB10
J 0
(-4300 10300);
DISPLAY 0.617021 (-4300 10300);
PAINT BLUE (-4300 10300);
DISPLAY INVISIBLE (-4300 10300);
FORCEPROP 1 LAST TOLERANCE 5%
J 0
(-4300 10400);
DISPLAY 0.617021 (-4300 10400);
PAINT SKYBLUE (-4300 10400);
FORCEPROP 1 LAST VOLTAGE 50V
J 0
(-4300 10450);
DISPLAY 0.617021 (-4300 10450);
PAINT SKYBLUE (-4300 10450);
FORCEPROP 1 LAST MATERIAL X7R
J 0
(-4300 10350);
DISPLAY 0.617021 (-4300 10350);
PAINT SKYBLUE (-4300 10350);
FORCEPROP 1 LAST VALUE 1000PF
J 0
(-4300 10500);
DISPLAY 0.617021 (-4300 10500);
PAINT SKYBLUE (-4300 10500);
FORCEPROP 1 LAST PACK_TYPE 0402
J 0
(-4300 10250);
DISPLAY 0.617021 (-4300 10250);
PAINT SKYBLUE (-4300 10250);
FORCEPROP 1 LAST LOCATION C1296
J 0
(-4300 10550);
DISPLAY 0.723404 (-4300 10550);
PAINT AQUA (-4300 10550);
FORCEPROP 1 LASTPIN (-4350 10550) $PN 1
J 0
(-4340 10530);
DISPLAY 0.617021 (-4340 10530);
FORCEPROP 1 LASTPIN (-4350 10350) $PN 2
J 0
(-4340 10330);
DISPLAY 0.617021 (-4340 10330);
FORCEPROP 2 LAST CDS_LIB pure_quanta
J 0
(-4350 10450);
PAINT MONO (-4350 10450);
DISPLAY INVISIBLE (-4350 10450);
FORCEPROP 1 LAST PATH I31
J 0
(-4300 10600);
DISPLAY 0.978723 (-4300 10600);
PAINT WHITE (-4300 10600);
DISPLAY INVISIBLE (-4300 10600);
FORCEPROP 2 LAST $SEC 1
J 0
(-4300 10650);
DISPLAY 0.680851 (-4300 10650);
PAINT MONO (-4300 10650);
DISPLAY INVISIBLE (-4300 10650);
FORCEPROP 2 LAST CDS_SEC 1
J 0
(-4300 10650);
DISPLAY 1.021277 (-4300 10650);
DISPLAY INVISIBLE (-4300 10650);
FORCEADD Q_RES..2
(-5425 10900);
FORCEPROP 1 LAST PART_NUMBER CS31002FB08
J 0
(-5385 10775);
DISPLAY 0.617021 (-5385 10775);
PAINT BLUE (-5385 10775);
DISPLAY INVISIBLE (-5385 10775);
FORCEPROP 1 LAST WATTAGE 1/16W
J 0
(-5385 10875);
DISPLAY 0.617021 (-5385 10875);
PAINT SKYBLUE (-5385 10875);
FORCEPROP 1 LAST TOLERANCE 1%
J 0
(-5380 10925);
DISPLAY 0.617021 (-5380 10925);
PAINT SKYBLUE (-5380 10925);
FORCEPROP 1 LAST MATERIAL CHIP
J 0
(-5385 10825);
DISPLAY 0.617021 (-5385 10825);
PAINT SKYBLUE (-5385 10825);
FORCEPROP 1 LAST PACK_TYPE 0402LF
J 0
(-5385 10725);
DISPLAY 0.617021 (-5385 10725);
PAINT SKYBLUE (-5385 10725);
FORCEPROP 1 LAST VALUE 10K
J 0
(-5380 10975);
DISPLAY 0.617021 (-5380 10975);
PAINT SKYBLUE (-5380 10975);
FORCEPROP 1 LAST LOCATION R2409
J 0
(-5380 11025);
DISPLAY 0.617021 (-5380 11025);
PAINT AQUA (-5380 11025);
FORCEPROP 1 LASTPIN (-5425 11000) $PN 1
J 0
(-5420 10962);
DISPLAY 0.617021 (-5420 10962);
FORCEPROP 1 LASTPIN (-5425 10800) $PN 2
J 0
(-5420 10810);
DISPLAY 0.617021 (-5420 10810);
FORCEPROP 2 LAST BOM_COST VR_PCH
J 0
(-5375 11075);
DISPLAY 0.680851 (-5375 11075);
DISPLAY INVISIBLE (-5375 11075);
FORCEPROP 2 LAST CDS_LIB pure_quanta
J 0
(-5425 10900);
DISPLAY INVISIBLE (-5425 10900);
FORCEPROP 1 LAST PATH I32
J 0
(-5375 11075);
DISPLAY 0.978723 (-5375 11075);
PAINT WHITE (-5375 11075);
DISPLAY INVISIBLE (-5375 11075);
FORCEPROP 0 LAST $SEC 1
J 0
(-5375 11125);
DISPLAY 0.680851 (-5375 11125);
PAINT MONO (-5375 11125);
DISPLAY INVISIBLE (-5375 11125);
FORCEPROP 0 LAST CDS_SEC 1
J 0
(-5375 11125);
DISPLAY 0.680851 (-5375 11125);
DISPLAY INVISIBLE (-5375 11125);
FORCEADD Q_RES..1
(-5075 10625);
FORCEPROP 1 LAST PART_NUMBER CS00002JB13
J 0
(-4950 10675);
DISPLAY 0.617021 (-4950 10675);
PAINT BLUE (-4950 10675);
DISPLAY INVISIBLE (-4950 10675);
FORCEPROP 1 LAST TOLERANCE 5%
J 0
(-4900 10625);
DISPLAY 0.617021 (-4900 10625);
PAINT SKYBLUE (-4900 10625);
FORCEPROP 1 LAST MATERIAL CHIP
J 0
(-4825 10625);
DISPLAY 0.617021 (-4825 10625);
PAINT SKYBLUE (-4825 10625);
FORCEPROP 1 LAST VALUE 0
J 2
(-4925 10625);
DISPLAY 0.617021 (-4925 10625);
PAINT SKYBLUE (-4925 10625);
FORCEPROP 1 LAST LOCATION R1652
J 0
(-5325 10625);
DISPLAY 0.723404 (-5325 10625);
PAINT AQUA (-5325 10625);
FORCEPROP 1 LASTPIN (-5175 10625) $PN 1
J 0
(-5163 10637);
DISPLAY 0.617021 (-5163 10637);
FORCEPROP 1 LASTPIN (-4975 10625) $PN 2
J 0
(-5013 10637);
DISPLAY 0.617021 (-5013 10637);
FORCEPROP 2 LAST CDS_LIB pure_quanta
J 0
(-5075 10625);
PAINT MONO (-5075 10625);
DISPLAY INVISIBLE (-5075 10625);
FORCEPROP 1 LAST PACK_TYPE 0402LF
J 0
(-5125 10725);
DISPLAY 0.404255 (-5125 10725);
PAINT SKYBLUE (-5125 10725);
DISPLAY INVISIBLE (-5125 10725);
FORCEPROP 1 LAST WATTAGE 1/16W
J 2
(-4900 10700);
DISPLAY 0.404255 (-4900 10700);
PAINT SKYBLUE (-4900 10700);
DISPLAY INVISIBLE (-4900 10700);
FORCEPROP 1 LAST PATH I33
J 0
(-5125 10775);
DISPLAY 0.978723 (-5125 10775);
PAINT WHITE (-5125 10775);
DISPLAY INVISIBLE (-5125 10775);
FORCEPROP 2 LAST $SEC 1
J 0
(-5125 10825);
DISPLAY 0.680851 (-5125 10825);
PAINT MONO (-5125 10825);
DISPLAY INVISIBLE (-5125 10825);
FORCEPROP 2 LAST CDS_SEC 1
J 0
(-5125 10825);
DISPLAY 1.021277 (-5125 10825);
DISPLAY INVISIBLE (-5125 10825);
FORCEADD VCCAUX15..1
(-5425 11150);
FORCEPROP 3 LASTPIN (-5425 11100) SIG_NAME P3V3_AUX\g
J 0
(-5415 11110);
DISPLAY 0.659574 (-5415 11110);
PAINT MONO (-5415 11110);
DISPLAY INVISIBLE (-5415 11110);
FORCEPROP 1 LAST HDL_POWER P3V3_AUX
J 1
(-5425 11192);
DISPLAY 0.617021 (-5425 11192);
PAINT GREEN (-5425 11192);
FORCEPROP 2 LAST CDS_LIB logical_power
J 0
(-5425 11150);
DISPLAY INVISIBLE (-5425 11150);
FORCEPROP 2 LAST BOM_COST VR_PCH
J 0
(-5425 11225);
DISPLAY 0.680851 (-5425 11225);
DISPLAY INVISIBLE (-5425 11225);
FORCEPROP 1 LAST PATH I34
J 0
(-5375 11175);
DISPLAY 0.872340 (-5375 11175);
PAINT AQUA (-5375 11175);
DISPLAY INVISIBLE (-5375 11175);
FORCEADD Q_CAP..2
(-3425 8650);
FORCEPROP 1 LAST PART_NUMBER TMP_QCH16806KB17
J 1
(-3050 8550);
DISPLAY 0.617021 (-3050 8550);
PAINT BLUE (-3050 8550);
DISPLAY INVISIBLE (-3050 8550);
FORCEPROP 1 LAST VALUE 680PF
J 2
(-3425 8550);
DISPLAY 0.617021 (-3425 8550);
PAINT SKYBLUE (-3425 8550);
FORCEPROP 1 LAST VOLTAGE 50V
J 0
(-3400 8550);
DISPLAY 0.617021 (-3400 8550);
PAINT SKYBLUE (-3400 8550);
FORCEPROP 1 LAST PACK_TYPE 0402
J 1
(-3425 8450);
DISPLAY 0.617021 (-3425 8450);
PAINT SKYBLUE (-3425 8450);
FORCEPROP 1 LAST MATERIAL X7R
J 0
(-3425 8500);
DISPLAY 0.617021 (-3425 8500);
PAINT SKYBLUE (-3425 8500);
FORCEPROP 1 LAST TOLERANCE 10%
J 2
(-3425 8500);
DISPLAY 0.617021 (-3425 8500);
PAINT SKYBLUE (-3425 8500);
FORCEPROP 1 LAST LOCATION PC237
J 1
(-3600 8675);
DISPLAY 0.617021 (-3600 8675);
PAINT AQUA (-3600 8675);
FORCEPROP 2 LAST CDS_LIB pure_quanta
J 0
(-3425 8650);
DISPLAY INVISIBLE (-3425 8650);
FORCEPROP 1 LAST PATH I35
J 0
(-3425 8850);
DISPLAY 0.978723 (-3425 8850);
PAINT WHITE (-3425 8850);
DISPLAY INVISIBLE (-3425 8850);
FORCEPROP 0 LAST $SEC 1
J 0
(-3600 8725);
DISPLAY 0.680851 (-3600 8725);
PAINT MONO (-3600 8725);
DISPLAY INVISIBLE (-3600 8725);
FORCEPROP 0 LAST CDS_SEC 1
J 0
(-3600 8725);
DISPLAY 1.021277 (-3600 8725);
DISPLAY INVISIBLE (-3600 8725);
FORCEPROP 1 LASTPIN (-3525 8650) $PN 1
J 0
(-3535 8665);
DISPLAY 0.808511 (-3535 8665);
PAINT WHITE (-3535 8665);
DISPLAY INVISIBLE (-3535 8665);
FORCEPROP 1 LASTPIN (-3325 8650) $PN 2
J 0
(-3340 8665);
DISPLAY 0.808511 (-3340 8665);
PAINT WHITE (-3340 8665);
DISPLAY INVISIBLE (-3340 8665);
FORCEADD Q_RES..1
(-3425 9000);
FORCEPROP 1 LAST PART_NUMBER CS28252BB01
J 0
(-3475 9100);
DISPLAY 0.617021 (-3475 9100);
PAINT BLUE (-3475 9100);
DISPLAY INVISIBLE (-3475 9100);
FORCEPROP 1 LAST PACK_TYPE 0402LF
J 0
(-3175 8850);
DISPLAY 0.617021 (-3175 8850);
PAINT SKYBLUE (-3175 8850);
FORCEPROP 1 LAST MATERIAL CHIP
J 0
(-3425 8850);
DISPLAY 0.617021 (-3425 8850);
PAINT SKYBLUE (-3425 8850);
FORCEPROP 1 LAST WATTAGE 1/16W
J 2
(-3450 8850);
DISPLAY 0.617021 (-3450 8850);
PAINT SKYBLUE (-3450 8850);
FORCEPROP 1 LAST VALUE 8.25K
J 2
(-3450 8900);
DISPLAY 0.617021 (-3450 8900);
PAINT SKYBLUE (-3450 8900);
FORCEPROP 1 LAST TOLERANCE 0.1%
J 0
(-3425 8900);
DISPLAY 0.617021 (-3425 8900);
PAINT SKYBLUE (-3425 8900);
FORCEPROP 1 LAST LOCATION PR501
J 0
(-3475 9050);
DISPLAY 0.617021 (-3475 9050);
PAINT AQUA (-3475 9050);
FORCEPROP 1 LASTPIN (-3525 9000) $PN 1
J 0
(-3513 9012);
DISPLAY 0.617021 (-3513 9012);
PAINT MONO (-3513 9012);
FORCEPROP 1 LASTPIN (-3325 9000) $PN 2
J 0
(-3363 9012);
DISPLAY 0.617021 (-3363 9012);
PAINT MONO (-3363 9012);
FORCEPROP 2 LAST CDS_LIB pure_quanta
J 0
(-3425 9000);
DISPLAY INVISIBLE (-3425 9000);
FORCEPROP 1 LAST PATH I36
J 0
(-3475 9150);
DISPLAY 0.978723 (-3475 9150);
PAINT WHITE (-3475 9150);
DISPLAY INVISIBLE (-3475 9150);
FORCEPROP 0 LAST $SEC 1
J 0
(-3475 9150);
DISPLAY 0.680851 (-3475 9150);
PAINT MONO (-3475 9150);
DISPLAY INVISIBLE (-3475 9150);
FORCEPROP 0 LAST CDS_SEC 1
J 0
(-3475 9150);
DISPLAY 1.021277 (-3475 9150);
DISPLAY INVISIBLE (-3475 9150);
FORCEADD Q_CAP..1
(-3425 9650);
FORCEPROP 1 LAST PART_NUMBER CH4106K1B01
J 0
(-3375 9450);
DISPLAY 0.617021 (-3375 9450);
PAINT BLUE (-3375 9450);
DISPLAY INVISIBLE (-3375 9450);
FORCEPROP 1 LAST TOLERANCE 10%
J 0
(-3375 9600);
DISPLAY 0.617021 (-3375 9600);
PAINT SKYBLUE (-3375 9600);
FORCEPROP 1 LAST VALUE 100NF
J 0
(-3375 9700);
DISPLAY 0.617021 (-3375 9700);
PAINT SKYBLUE (-3375 9700);
FORCEPROP 1 LAST MATERIAL X7R
J 0
(-3375 9550);
DISPLAY 0.617021 (-3375 9550);
PAINT SKYBLUE (-3375 9550);
FORCEPROP 1 LAST PACK_TYPE C0402
J 0
(-3375 9500);
DISPLAY 0.617021 (-3375 9500);
PAINT SKYBLUE (-3375 9500);
FORCEPROP 1 LAST VOLTAGE 50V
J 0
(-3375 9650);
DISPLAY 0.617021 (-3375 9650);
PAINT SKYBLUE (-3375 9650);
FORCEPROP 1 LAST LOCATION PC1276
J 0
(-3375 9750);
DISPLAY 0.617021 (-3375 9750);
PAINT AQUA (-3375 9750);
FORCEPROP 1 LASTPIN (-3425 9750) $PN 1
J 0
(-3415 9730);
DISPLAY 0.617021 (-3415 9730);
FORCEPROP 1 LASTPIN (-3425 9550) $PN 2
J 0
(-3415 9530);
DISPLAY 0.617021 (-3415 9530);
FORCEPROP 2 LAST CDS_LIB pure_quanta
J 0
(-3425 9650);
PAINT MONO (-3425 9650);
DISPLAY INVISIBLE (-3425 9650);
FORCEPROP 1 LAST PATH I37
J 0
(-3375 9800);
DISPLAY 0.978723 (-3375 9800);
PAINT WHITE (-3375 9800);
DISPLAY INVISIBLE (-3375 9800);
FORCEPROP 2 LAST $SEC 1
J 0
(-3375 9850);
DISPLAY 0.680851 (-3375 9850);
PAINT MONO (-3375 9850);
DISPLAY INVISIBLE (-3375 9850);
FORCEPROP 2 LAST CDS_SEC 1
J 0
(-3375 9850);
DISPLAY 1.021277 (-3375 9850);
DISPLAY INVISIBLE (-3375 9850);
FORCEADD Q_CAP..1
(-3050 9650);
FORCEPROP 1 LAST PART_NUMBER CH622KMEA03
J 0
(-3000 9450);
DISPLAY 0.617021 (-3000 9450);
PAINT BLUE (-3000 9450);
DISPLAY INVISIBLE (-3000 9450);
FORCEPROP 1 LAST PACK_TYPE C0805
J 0
(-3000 9500);
DISPLAY 0.617021 (-3000 9500);
PAINT SKYBLUE (-3000 9500);
FORCEPROP 1 LAST TOLERANCE 20%
J 0
(-3000 9600);
DISPLAY 0.617021 (-3000 9600);
PAINT SKYBLUE (-3000 9600);
FORCEPROP 1 LAST VOLTAGE 4V
J 0
(-3000 9650);
DISPLAY 0.617021 (-3000 9650);
PAINT SKYBLUE (-3000 9650);
FORCEPROP 1 LAST VALUE 22UF
J 0
(-3000 9700);
DISPLAY 0.617021 (-3000 9700);
PAINT SKYBLUE (-3000 9700);
FORCEPROP 1 LAST MATERIAL X6S
J 0
(-3000 9550);
DISPLAY 0.617021 (-3000 9550);
PAINT SKYBLUE (-3000 9550);
FORCEPROP 1 LAST LOCATION PC1277
J 0
(-3000 9750);
DISPLAY 0.617021 (-3000 9750);
PAINT AQUA (-3000 9750);
FORCEPROP 1 LASTPIN (-3050 9750) $PN 1
J 0
(-3040 9730);
DISPLAY 0.617021 (-3040 9730);
FORCEPROP 1 LASTPIN (-3050 9550) $PN 2
J 0
(-3040 9530);
DISPLAY 0.617021 (-3040 9530);
FORCEPROP 2 LAST BOM_COST VR_PCH
J 0
(-3000 9800);
DISPLAY 0.680851 (-3000 9800);
DISPLAY INVISIBLE (-3000 9800);
FORCEPROP 2 LAST CDS_LIB pure_quanta
J 0
(-3050 9650);
PAINT MONO (-3050 9650);
DISPLAY INVISIBLE (-3050 9650);
FORCEPROP 1 LAST PATH I38
J 0
(-3000 9800);
DISPLAY 0.978723 (-3000 9800);
PAINT WHITE (-3000 9800);
DISPLAY INVISIBLE (-3000 9800);
FORCEPROP 2 LAST $SEC 1
J 0
(-3000 9850);
DISPLAY 0.680851 (-3000 9850);
PAINT MONO (-3000 9850);
DISPLAY INVISIBLE (-3000 9850);
FORCEPROP 2 LAST CDS_SEC 1
J 0
(-3000 9850);
DISPLAY 1.021277 (-3000 9850);
DISPLAY INVISIBLE (-3000 9850);
FORCEADD Q_CAP..1
(-2725 8700);
FORCEPROP 1 LAST PART_NUMBER TMP_QCH31004KB17
J 0
(-2675 8550);
DISPLAY 0.617021 (-2675 8550);
PAINT BLUE (-2675 8550);
DISPLAY INVISIBLE (-2675 8550);
FORCEPROP 1 LAST TOLERANCE 10%
J 0
(-2675 8650);
DISPLAY 0.617021 (-2675 8650);
PAINT SKYBLUE (-2675 8650);
FORCEPROP 1 LAST MATERIAL X7R
J 0
(-2675 8600);
DISPLAY 0.617021 (-2675 8600);
PAINT SKYBLUE (-2675 8600);
FORCEPROP 1 LAST VALUE 0.01UF
J 0
(-2675 8750);
DISPLAY 0.617021 (-2675 8750);
PAINT SKYBLUE (-2675 8750);
FORCEPROP 1 LAST PACK_TYPE 0402
J 0
(-2675 8500);
DISPLAY 0.617021 (-2675 8500);
PAINT SKYBLUE (-2675 8500);
FORCEPROP 1 LAST VOLTAGE 25V
J 0
(-2675 8700);
DISPLAY 0.617021 (-2675 8700);
PAINT SKYBLUE (-2675 8700);
FORCEPROP 1 LAST LOCATION PC1420
J 0
(-2675 8800);
DISPLAY 0.617021 (-2675 8800);
PAINT AQUA (-2675 8800);
FORCEPROP 1 LASTPIN (-2725 8800) $PN 1
J 0
(-2715 8780);
DISPLAY 0.787234 (-2715 8780);
PAINT MONO (-2715 8780);
FORCEPROP 1 LASTPIN (-2725 8600) $PN 2
J 0
(-2715 8580);
DISPLAY 0.787234 (-2715 8580);
PAINT MONO (-2715 8580);
FORCEPROP 2 LAST CDS_LIB pure_quanta
J 0
(-2725 8700);
DISPLAY INVISIBLE (-2725 8700);
FORCEPROP 1 LAST PATH I39
J 0
(-2675 8850);
DISPLAY 0.978723 (-2675 8850);
PAINT WHITE (-2675 8850);
DISPLAY INVISIBLE (-2675 8850);
FORCEPROP 0 LAST $SEC 1
J 0
(-2675 8850);
DISPLAY 0.680851 (-2675 8850);
PAINT MONO (-2675 8850);
DISPLAY INVISIBLE (-2675 8850);
FORCEPROP 0 LAST CDS_SEC 1
J 0
(-2675 8850);
DISPLAY 1.021277 (-2675 8850);
DISPLAY INVISIBLE (-2675 8850);
FORCEADD Q_CAP..1
R 2
(-9225 9675);
FORCEPROP 1 LAST PART_NUMBER TMP_QCH21006JB10
J 2
(-9275 9550);
DISPLAY 0.617021 (-9275 9550);
PAINT BLUE (-9275 9550);
DISPLAY INVISIBLE (-9275 9550);
FORCEPROP 1 LAST VALUE 1000PF
J 2
(-9275 9750);
DISPLAY 0.617021 (-9275 9750);
PAINT SKYBLUE (-9275 9750);
FORCEPROP 1 LAST PACK_TYPE 0402
J 2
(-9275 9500);
DISPLAY 0.617021 (-9275 9500);
PAINT SKYBLUE (-9275 9500);
FORCEPROP 1 LAST VOLTAGE 50V
J 2
(-9275 9700);
DISPLAY 0.617021 (-9275 9700);
PAINT SKYBLUE (-9275 9700);
FORCEPROP 1 LAST TOLERANCE 5%
J 2
(-9275 9650);
DISPLAY 0.617021 (-9275 9650);
PAINT SKYBLUE (-9275 9650);
FORCEPROP 1 LAST MATERIAL EMPTY
J 2
(-9275 9600);
DISPLAY 0.617021 (-9275 9600);
PAINT RED (-9275 9600);
FORCEPROP 1 LAST LOCATION C1307
J 2
(-9275 9800);
DISPLAY 0.723404 (-9275 9800);
PAINT AQUA (-9275 9800);
FORCEPROP 1 LASTPIN (-9225 9775) $PN 1
J 2
(-9235 9755);
DISPLAY 0.617021 (-9235 9755);
FORCEPROP 1 LASTPIN (-9225 9575) $PN 2
J 2
(-9235 9555);
DISPLAY 0.617021 (-9235 9555);
FORCEPROP 2 LAST CDS_LIB pure_quanta
J 0
(-9225 9675);
PAINT MONO (-9225 9675);
DISPLAY INVISIBLE (-9225 9675);
FORCEPROP 1 LAST PATH I4
J 2
(-9275 9825);
DISPLAY 0.978723 (-9275 9825);
PAINT WHITE (-9275 9825);
DISPLAY INVISIBLE (-9275 9825);
FORCEPROP 2 LAST $SEC 1
J 0
(-9275 9875);
DISPLAY 0.680851 (-9275 9875);
PAINT MONO (-9275 9875);
DISPLAY INVISIBLE (-9275 9875);
FORCEPROP 2 LAST CDS_SEC 1
J 0
(-9275 9875);
DISPLAY 1.021277 (-9275 9875);
DISPLAY INVISIBLE (-9275 9875);
FORCEADD Q_RES..1
(-2075 8750);
FORCEPROP 1 LAST PART_NUMBER CS00002JB13
J 0
(-2225 8675);
DISPLAY 0.617021 (-2225 8675);
PAINT BLUE (-2225 8675);
DISPLAY INVISIBLE (-2225 8675);
FORCEPROP 1 LAST VALUE 0
J 2
(-2100 8800);
DISPLAY 0.617021 (-2100 8800);
PAINT SKYBLUE (-2100 8800);
FORCEPROP 1 LAST TOLERANCE 5%
J 0
(-2025 8800);
DISPLAY 0.617021 (-2025 8800);
PAINT SKYBLUE (-2025 8800);
FORCEPROP 1 LAST PACK_TYPE 0402LF
J 0
(-2050 8625);
DISPLAY 0.638298 (-2050 8625);
PAINT SKYBLUE (-2050 8625);
FORCEPROP 1 LAST MATERIAL EMPTY
J 0
(-2225 8625);
DISPLAY 0.617021 (-2225 8625);
PAINT RED (-2225 8625);
FORCEPROP 1 LAST LOCATION PR4698
J 0
(-2300 8750);
DISPLAY 0.638298 (-2300 8750);
PAINT AQUA (-2300 8750);
FORCEPROP 1 LASTPIN (-2175 8750) $PN 1
J 0
(-2163 8762);
DISPLAY 0.787234 (-2163 8762);
PAINT MONO (-2163 8762);
FORCEPROP 1 LASTPIN (-1975 8750) $PN 2
J 0
(-2013 8762);
DISPLAY 0.787234 (-2013 8762);
PAINT MONO (-2013 8762);
FORCEPROP 2 LAST CDS_LIB pure_quanta
J 0
(-2075 8750);
DISPLAY INVISIBLE (-2075 8750);
FORCEPROP 1 LAST WATTAGE 1/16W
J 2
(-1900 8825);
DISPLAY 0.404255 (-1900 8825);
PAINT SKYBLUE (-1900 8825);
DISPLAY INVISIBLE (-1900 8825);
FORCEPROP 1 LAST PATH I40
J 0
(-2125 8900);
DISPLAY 0.978723 (-2125 8900);
PAINT WHITE (-2125 8900);
DISPLAY INVISIBLE (-2125 8900);
FORCEPROP 0 LAST $SEC 1
J 0
(-2025 8850);
DISPLAY 0.680851 (-2025 8850);
PAINT MONO (-2025 8850);
DISPLAY INVISIBLE (-2025 8850);
FORCEPROP 0 LAST CDS_SEC 1
J 0
(-2025 8850);
DISPLAY 1.021277 (-2025 8850);
DISPLAY INVISIBLE (-2025 8850);
FORCEADD Q_RES..1
(-2075 9000);
FORCEPROP 1 LAST PART_NUMBER CS00002JB13
J 0
(-2225 8925);
DISPLAY 0.617021 (-2225 8925);
PAINT BLUE (-2225 8925);
DISPLAY INVISIBLE (-2225 8925);
FORCEPROP 1 LAST PACK_TYPE 0402LF
J 0
(-2050 8875);
DISPLAY 0.638298 (-2050 8875);
PAINT SKYBLUE (-2050 8875);
FORCEPROP 1 LAST MATERIAL CHIP
J 0
(-2225 8875);
DISPLAY 0.617021 (-2225 8875);
PAINT SKYBLUE (-2225 8875);
FORCEPROP 1 LAST TOLERANCE 5%
J 0
(-2025 9050);
DISPLAY 0.617021 (-2025 9050);
PAINT SKYBLUE (-2025 9050);
FORCEPROP 1 LAST VALUE 0
J 2
(-2100 9050);
DISPLAY 0.617021 (-2100 9050);
PAINT SKYBLUE (-2100 9050);
FORCEPROP 1 LAST LOCATION PR4683
J 0
(-2300 9000);
DISPLAY 0.638298 (-2300 9000);
PAINT AQUA (-2300 9000);
FORCEPROP 1 LASTPIN (-2175 9000) $PN 1
J 0
(-2163 9012);
DISPLAY 0.787234 (-2163 9012);
PAINT MONO (-2163 9012);
FORCEPROP 1 LASTPIN (-1975 9000) $PN 2
J 0
(-2013 9012);
DISPLAY 0.787234 (-2013 9012);
PAINT MONO (-2013 9012);
FORCEPROP 2 LAST CDS_LIB pure_quanta
J 0
(-2075 9000);
DISPLAY INVISIBLE (-2075 9000);
FORCEPROP 1 LAST WATTAGE 1/16W
J 2
(-1900 9075);
DISPLAY 0.404255 (-1900 9075);
PAINT SKYBLUE (-1900 9075);
DISPLAY INVISIBLE (-1900 9075);
FORCEPROP 1 LAST PATH I41
J 0
(-2125 9150);
DISPLAY 0.978723 (-2125 9150);
PAINT WHITE (-2125 9150);
DISPLAY INVISIBLE (-2125 9150);
FORCEPROP 0 LAST $SEC 1
J 0
(-2025 9100);
DISPLAY 0.680851 (-2025 9100);
PAINT MONO (-2025 9100);
DISPLAY INVISIBLE (-2025 9100);
FORCEPROP 0 LAST CDS_SEC 1
J 0
(-2025 9100);
DISPLAY 1.021277 (-2025 9100);
DISPLAY INVISIBLE (-2025 9100);
FORCEADD Q_CAP..1
(-2675 9650);
FORCEPROP 1 LAST PART_NUMBER CH622KMEA03
J 0
(-2625 9450);
DISPLAY 0.617021 (-2625 9450);
PAINT BLUE (-2625 9450);
DISPLAY INVISIBLE (-2625 9450);
FORCEPROP 1 LAST TOLERANCE 20%
J 0
(-2625 9600);
DISPLAY 0.617021 (-2625 9600);
PAINT SKYBLUE (-2625 9600);
FORCEPROP 1 LAST MATERIAL X6S
J 0
(-2625 9550);
DISPLAY 0.617021 (-2625 9550);
PAINT SKYBLUE (-2625 9550);
FORCEPROP 1 LAST PACK_TYPE C0805
J 0
(-2625 9500);
DISPLAY 0.617021 (-2625 9500);
PAINT SKYBLUE (-2625 9500);
FORCEPROP 1 LAST VOLTAGE 4V
J 0
(-2625 9650);
DISPLAY 0.617021 (-2625 9650);
PAINT SKYBLUE (-2625 9650);
FORCEPROP 1 LAST VALUE 22UF
J 0
(-2625 9700);
DISPLAY 0.617021 (-2625 9700);
PAINT SKYBLUE (-2625 9700);
FORCEPROP 1 LAST LOCATION PC1278
J 0
(-2625 9750);
DISPLAY 0.617021 (-2625 9750);
PAINT AQUA (-2625 9750);
FORCEPROP 1 LASTPIN (-2675 9750) $PN 1
J 0
(-2665 9730);
DISPLAY 0.617021 (-2665 9730);
FORCEPROP 1 LASTPIN (-2675 9550) $PN 2
J 0
(-2665 9530);
DISPLAY 0.617021 (-2665 9530);
FORCEPROP 2 LAST CDS_LIB pure_quanta
J 0
(-2675 9650);
PAINT MONO (-2675 9650);
DISPLAY INVISIBLE (-2675 9650);
FORCEPROP 2 LAST BOM_COST VR_PCH
J 0
(-2625 9800);
DISPLAY 0.680851 (-2625 9800);
DISPLAY INVISIBLE (-2625 9800);
FORCEPROP 1 LAST PATH I42
J 0
(-2625 9800);
DISPLAY 0.978723 (-2625 9800);
PAINT WHITE (-2625 9800);
DISPLAY INVISIBLE (-2625 9800);
FORCEPROP 2 LAST $SEC 1
J 0
(-2625 9850);
DISPLAY 0.680851 (-2625 9850);
PAINT MONO (-2625 9850);
DISPLAY INVISIBLE (-2625 9850);
FORCEPROP 2 LAST CDS_SEC 1
J 0
(-2625 9850);
DISPLAY 1.021277 (-2625 9850);
DISPLAY INVISIBLE (-2625 9850);
FORCEADD Q_CAP..1
(-2300 9650);
FORCEPROP 1 LAST PART_NUMBER CH622KMEA03
J 0
(-2250 9450);
DISPLAY 0.617021 (-2250 9450);
PAINT BLUE (-2250 9450);
DISPLAY INVISIBLE (-2250 9450);
FORCEPROP 1 LAST VALUE 22UF
J 0
(-2250 9700);
DISPLAY 0.617021 (-2250 9700);
PAINT SKYBLUE (-2250 9700);
FORCEPROP 1 LAST VOLTAGE 4V
J 0
(-2250 9650);
DISPLAY 0.617021 (-2250 9650);
PAINT SKYBLUE (-2250 9650);
FORCEPROP 1 LAST TOLERANCE 20%
J 0
(-2250 9600);
DISPLAY 0.617021 (-2250 9600);
PAINT SKYBLUE (-2250 9600);
FORCEPROP 1 LAST MATERIAL X6S
J 0
(-2250 9550);
DISPLAY 0.617021 (-2250 9550);
PAINT SKYBLUE (-2250 9550);
FORCEPROP 1 LAST PACK_TYPE C0805
J 0
(-2250 9500);
DISPLAY 0.617021 (-2250 9500);
PAINT SKYBLUE (-2250 9500);
FORCEPROP 1 LAST LOCATION PC1279
J 0
(-2250 9750);
DISPLAY 0.617021 (-2250 9750);
PAINT AQUA (-2250 9750);
FORCEPROP 1 LASTPIN (-2300 9750) $PN 1
J 0
(-2290 9730);
DISPLAY 0.617021 (-2290 9730);
FORCEPROP 1 LASTPIN (-2300 9550) $PN 2
J 0
(-2290 9530);
DISPLAY 0.617021 (-2290 9530);
FORCEPROP 2 LAST CDS_LIB pure_quanta
J 0
(-2300 9650);
PAINT MONO (-2300 9650);
DISPLAY INVISIBLE (-2300 9650);
FORCEPROP 2 LAST BOM_COST VR_PCH
J 0
(-2250 9800);
DISPLAY 0.680851 (-2250 9800);
DISPLAY INVISIBLE (-2250 9800);
FORCEPROP 1 LAST PATH I43
J 0
(-2250 9800);
DISPLAY 0.978723 (-2250 9800);
PAINT WHITE (-2250 9800);
DISPLAY INVISIBLE (-2250 9800);
FORCEPROP 2 LAST $SEC 1
J 0
(-2250 9850);
DISPLAY 0.680851 (-2250 9850);
PAINT MONO (-2250 9850);
DISPLAY INVISIBLE (-2250 9850);
FORCEPROP 2 LAST CDS_SEC 1
J 0
(-2250 9850);
DISPLAY 1.021277 (-2250 9850);
DISPLAY INVISIBLE (-2250 9850);
FORCEADD OFFPAGE..2
(-3575 10625);
FORCEPROP 2 LAST $XR2 253 
J 0
(-3146 10625);
DISPLAY 0.638298 (-3146 10625);
PAINT MONO (-3146 10625);
FORCEPROP 2 LAST $XR1 132 
J 0
(-3266 10625);
DISPLAY 0.638298 (-3266 10625);
PAINT MONO (-3266 10625);
FORCEPROP 2 LAST $XR0 213 
J 0
(-3386 10625);
DISPLAY 0.638298 (-3386 10625);
PAINT MONO (-3386 10625);
FORCEPROP 2 LAST CDS_LIB standard
J 0
(-3575 10625);
PAINT MONO (-3575 10625);
DISPLAY INVISIBLE (-3575 10625);
FORCEPROP 2 LAST BOM_COST VR_SYSTEM
J 0
(-3225 10675);
DISPLAY 0.680851 (-3225 10675);
DISPLAY INVISIBLE (-3225 10675);
FORCEPROP 1 LAST OFFPAGE TRUE
J 0
(-3250 10500);
DISPLAY 0.531915 (-3250 10500);
PAINT GREEN (-3250 10500);
DISPLAY INVISIBLE (-3250 10500);
FORCEPROP 1 LAST COMMENT_BODY TRUE
J 0
(-3620 10530);
DISPLAY 0.531915 (-3620 10530);
PAINT GREEN (-3620 10530);
DISPLAY INVISIBLE (-3620 10530);
FORCEPROP 2 LAST PATH I44
J 0
(-3125 10675);
DISPLAY 1.021277 (-3125 10675);
DISPLAY INVISIBLE (-3125 10675);
FORCEADD UNIVERSAL_GND..1
(-1900 9275);
FORCEPROP 3 LASTPIN (-1900 9325) SIG_NAME GND\g
J 0
(-1890 9335);
DISPLAY 0.659574 (-1890 9335);
PAINT MONO (-1890 9335);
DISPLAY INVISIBLE (-1890 9335);
FORCEPROP 2 LAST CDS_LIB logical_power
J 0
(-1900 9275);
DISPLAY INVISIBLE (-1900 9275);
FORCEPROP 1 LAST HDL_POWER GND
J 1
(-1875 9200);
DISPLAY 0.872340 (-1875 9200);
PAINT GREEN (-1875 9200);
DISPLAY INVISIBLE (-1875 9200);
FORCEPROP 1 LAST PATH I45
J 0
(-1825 9275);
DISPLAY 0.872340 (-1825 9275);
PAINT AQUA (-1825 9275);
DISPLAY INVISIBLE (-1825 9275);
FORCEADD VCCAUX15..1
(-1525 8850);
FORCEPROP 3 LASTPIN (-1525 8800) SIG_NAME PVNN_MAIN_CPU0\g
J 0
(-1515 8810);
DISPLAY 0.659574 (-1515 8810);
PAINT MONO (-1515 8810);
DISPLAY INVISIBLE (-1515 8810);
FORCEPROP 1 LAST HDL_POWER PVNN_MAIN_CPU0
J 1
(-1525 8900);
DISPLAY 0.617021 (-1525 8900);
PAINT GREEN (-1525 8900);
FORCEPROP 2 LAST CDS_LIB logical_power
J 0
(-1525 8850);
DISPLAY INVISIBLE (-1525 8850);
FORCEPROP 1 LAST PATH I46
J 0
(-1475 8875);
DISPLAY 0.872340 (-1475 8875);
PAINT AQUA (-1475 8875);
DISPLAY INVISIBLE (-1475 8875);
FORCEADD Q_CAP..1
(-1900 9650);
FORCEPROP 1 LAST PART_NUMBER CH622KMEA03
J 0
(-1850 9450);
DISPLAY 0.617021 (-1850 9450);
PAINT BLUE (-1850 9450);
DISPLAY INVISIBLE (-1850 9450);
FORCEPROP 1 LAST PACK_TYPE C0805
J 0
(-1850 9500);
DISPLAY 0.617021 (-1850 9500);
PAINT SKYBLUE (-1850 9500);
FORCEPROP 1 LAST MATERIAL X6S
J 0
(-1850 9550);
DISPLAY 0.617021 (-1850 9550);
PAINT SKYBLUE (-1850 9550);
FORCEPROP 1 LAST TOLERANCE 20%
J 0
(-1850 9600);
DISPLAY 0.617021 (-1850 9600);
PAINT SKYBLUE (-1850 9600);
FORCEPROP 1 LAST VOLTAGE 4V
J 0
(-1850 9650);
DISPLAY 0.617021 (-1850 9650);
PAINT SKYBLUE (-1850 9650);
FORCEPROP 1 LAST VALUE 22UF
J 0
(-1850 9700);
DISPLAY 0.617021 (-1850 9700);
PAINT SKYBLUE (-1850 9700);
FORCEPROP 1 LAST LOCATION PC1206
J 0
(-1850 9750);
DISPLAY 0.617021 (-1850 9750);
PAINT AQUA (-1850 9750);
FORCEPROP 1 LASTPIN (-1900 9750) $PN 1
J 0
(-1890 9730);
DISPLAY 0.617021 (-1890 9730);
PAINT MONO (-1890 9730);
FORCEPROP 1 LASTPIN (-1900 9550) $PN 2
J 0
(-1890 9530);
DISPLAY 0.617021 (-1890 9530);
PAINT MONO (-1890 9530);
FORCEPROP 2 LAST CDS_LIB pure_quanta
J 0
(-1900 9650);
DISPLAY INVISIBLE (-1900 9650);
FORCEPROP 2 LAST BOM_COST VR_PCH
J 0
(-1850 9800);
DISPLAY 0.680851 (-1850 9800);
DISPLAY INVISIBLE (-1850 9800);
FORCEPROP 1 LAST PATH I47
J 0
(-1850 9800);
DISPLAY 0.978723 (-1850 9800);
PAINT WHITE (-1850 9800);
DISPLAY INVISIBLE (-1850 9800);
FORCEPROP 2 LAST $SEC 1
J 0
(-1850 9850);
DISPLAY 0.680851 (-1850 9850);
PAINT MONO (-1850 9850);
DISPLAY INVISIBLE (-1850 9850);
FORCEPROP 2 LAST CDS_SEC 1
J 0
(-1850 9850);
DISPLAY 1.021277 (-1850 9850);
DISPLAY INVISIBLE (-1850 9850);
FORCEADD VCCAUX15..1
(-1525 10100);
FORCEPROP 3 LASTPIN (-1525 10050) SIG_NAME PVNN_MAIN_CPU0\g
J 0
(-1515 10060);
DISPLAY 0.659574 (-1515 10060);
PAINT MONO (-1515 10060);
DISPLAY INVISIBLE (-1515 10060);
FORCEPROP 1 LAST HDL_POWER PVNN_MAIN_CPU0
J 1
(-1525 10150);
DISPLAY 0.617021 (-1525 10150);
PAINT GREEN (-1525 10150);
FORCEPROP 2 LAST CDS_LIB logical_power
J 0
(-1525 10100);
DISPLAY INVISIBLE (-1525 10100);
FORCEPROP 1 LAST PATH I48
J 0
(-1475 10125);
DISPLAY 0.872340 (-1475 10125);
PAINT AQUA (-1475 10125);
DISPLAY INVISIBLE (-1475 10125);
FORCEADD Q_RES..1
(-9600 10050);
FORCEPROP 1 LAST PART_NUMBER CS31002FB08
J 0
(-9750 10125);
DISPLAY 0.617021 (-9750 10125);
PAINT BLUE (-9750 10125);
DISPLAY INVISIBLE (-9750 10125);
FORCEPROP 1 LAST WATTAGE 1/16W
J 2
(-9375 10150);
DISPLAY 0.617021 (-9375 10150);
PAINT SKYBLUE (-9375 10150);
FORCEPROP 1 LAST MATERIAL EMPTY
J 0
(-9350 10050);
DISPLAY 0.617021 (-9350 10050);
PAINT RED (-9350 10050);
FORCEPROP 1 LAST TOLERANCE 1%
J 0
(-9425 10050);
DISPLAY 0.617021 (-9425 10050);
PAINT SKYBLUE (-9425 10050);
FORCEPROP 1 LAST PACK_TYPE 0402LF
J 0
(-9750 10150);
DISPLAY 0.617021 (-9750 10150);
PAINT SKYBLUE (-9750 10150);
FORCEPROP 1 LAST VALUE 10K
J 2
(-9450 10050);
DISPLAY 0.617021 (-9450 10050);
PAINT SKYBLUE (-9450 10050);
FORCEPROP 1 LAST LOCATION R2338
J 0
(-9850 10050);
DISPLAY 0.723404 (-9850 10050);
PAINT AQUA (-9850 10050);
FORCEPROP 1 LASTPIN (-9700 10050) $PN 1
J 0
(-9688 10062);
DISPLAY 0.617021 (-9688 10062);
FORCEPROP 1 LASTPIN (-9500 10050) $PN 2
J 0
(-9538 10062);
DISPLAY 0.617021 (-9538 10062);
FORCEPROP 2 LAST CDS_LIB pure_quanta
J 0
(-9600 10050);
PAINT MONO (-9600 10050);
DISPLAY INVISIBLE (-9600 10050);
FORCEPROP 1 LAST PATH I5
J 0
(-9650 10200);
DISPLAY 0.978723 (-9650 10200);
PAINT WHITE (-9650 10200);
DISPLAY INVISIBLE (-9650 10200);
FORCEPROP 2 LAST $SEC 1
J 0
(-9650 10250);
DISPLAY 0.680851 (-9650 10250);
PAINT MONO (-9650 10250);
DISPLAY INVISIBLE (-9650 10250);
FORCEPROP 2 LAST CDS_SEC 1
J 0
(-9650 10250);
DISPLAY 1.021277 (-9650 10250);
DISPLAY INVISIBLE (-9650 10250);
FORCEADD UNIVERSAL_GND..1
(-9125 9450);
FORCEPROP 3 LASTPIN (-9125 9500) SIG_NAME GND\g
J 0
(-9115 9510);
DISPLAY 0.659574 (-9115 9510);
PAINT MONO (-9115 9510);
DISPLAY INVISIBLE (-9115 9510);
FORCEPROP 2 LAST CDS_LIB logical_power
J 0
(-9125 9450);
PAINT MONO (-9125 9450);
DISPLAY INVISIBLE (-9125 9450);
FORCEPROP 1 LAST HDL_POWER GND
J 1
(-9100 9375);
DISPLAY 0.872340 (-9100 9375);
PAINT GREEN (-9100 9375);
DISPLAY INVISIBLE (-9100 9375);
FORCEPROP 1 LAST PATH I6
J 0
(-9050 9450);
DISPLAY 0.872340 (-9050 9450);
PAINT AQUA (-9050 9450);
DISPLAY INVISIBLE (-9050 9450);
FORCEADD Q_CAP..1
(-8225 8725);
FORCEPROP 1 LAST PART_NUMBER CH5104KEB02
J 0
(-8175 8575);
DISPLAY 0.617021 (-8175 8575);
PAINT BLUE (-8175 8575);
DISPLAY INVISIBLE (-8175 8575);
FORCEPROP 1 LAST PACK_TYPE C0402
J 0
(-8175 8525);
DISPLAY 0.617021 (-8175 8525);
PAINT SKYBLUE (-8175 8525);
FORCEPROP 1 LAST TOLERANCE 10%
J 0
(-8175 8675);
DISPLAY 0.617021 (-8175 8675);
PAINT SKYBLUE (-8175 8675);
FORCEPROP 1 LAST VOLTAGE 25V
J 0
(-8175 8725);
DISPLAY 0.617021 (-8175 8725);
PAINT SKYBLUE (-8175 8725);
FORCEPROP 1 LAST VALUE 1UF
J 0
(-8175 8775);
DISPLAY 0.617021 (-8175 8775);
PAINT SKYBLUE (-8175 8775);
FORCEPROP 1 LAST MATERIAL X6S
J 0
(-8175 8625);
DISPLAY 0.617021 (-8175 8625);
PAINT SKYBLUE (-8175 8625);
FORCEPROP 1 LAST LOCATION PC2221
J 0
(-8175 8825);
DISPLAY 0.617021 (-8175 8825);
PAINT AQUA (-8175 8825);
FORCEPROP 1 LASTPIN (-8225 8825) $PN 1
J 0
(-8215 8805);
DISPLAY 0.617021 (-8215 8805);
PAINT WHITE (-8215 8805);
FORCEPROP 1 LASTPIN (-8225 8625) $PN 2
J 0
(-8215 8605);
DISPLAY 0.617021 (-8215 8605);
PAINT WHITE (-8215 8605);
FORCEPROP 2 LAST SEC_TYPE C0402
J 0
(-8175 8925);
DISPLAY 1.021277 (-8175 8925);
DISPLAY INVISIBLE (-8175 8925);
FORCEPROP 2 LAST CDS_LIB pure_quanta
J 0
(-8225 8725);
DISPLAY INVISIBLE (-8225 8725);
FORCEPROP 1 LAST PATH I7
J 0
(-8175 8875);
DISPLAY 0.978723 (-8175 8875);
PAINT WHITE (-8175 8875);
DISPLAY INVISIBLE (-8175 8875);
FORCEPROP 2 LAST SEC 1
J 0
(-8175 8925);
DISPLAY 0.680851 (-8175 8925);
PAINT MONO (-8175 8925);
DISPLAY INVISIBLE (-8175 8925);
FORCEADD UNIVERSAL_GND..1
(-8650 8975);
FORCEPROP 3 LASTPIN (-8650 9025) SIG_NAME GND\g
J 0
(-8640 9035);
DISPLAY 0.659574 (-8640 9035);
PAINT MONO (-8640 9035);
DISPLAY INVISIBLE (-8640 9035);
FORCEPROP 2 LAST CDS_LIB logical_power
J 0
(-8650 8975);
DISPLAY INVISIBLE (-8650 8975);
FORCEPROP 1 LAST HDL_POWER GND
J 1
(-8625 8900);
DISPLAY 0.702128 (-8625 8900);
PAINT GREEN (-8625 8900);
DISPLAY INVISIBLE (-8625 8900);
FORCEPROP 1 LAST PATH I8
J 0
(-8575 8975);
DISPLAY 0.872340 (-8575 8975);
PAINT AQUA (-8575 8975);
DISPLAY INVISIBLE (-8575 8975);
FORCEADD Q_RES..2
(-8650 9275);
FORCEPROP 1 LAST PART_NUMBER CS36042FB04
J 0
(-8610 9121);
DISPLAY 0.617021 (-8610 9121);
PAINT BLUE (-8610 9121);
DISPLAY INVISIBLE (-8610 9121);
FORCEPROP 1 LAST VALUE 60.4K
J 0
(-8605 9321);
DISPLAY 0.617021 (-8605 9321);
PAINT SKYBLUE (-8605 9321);
FORCEPROP 1 LAST PACK_TYPE 0402LF
J 0
(-8610 9071);
DISPLAY 0.617021 (-8610 9071);
PAINT SKYBLUE (-8610 9071);
FORCEPROP 1 LAST TOLERANCE 1%
J 0
(-8605 9271);
DISPLAY 0.617021 (-8605 9271);
PAINT SKYBLUE (-8605 9271);
FORCEPROP 1 LAST WATTAGE 1/16W
J 0
(-8610 9221);
DISPLAY 0.617021 (-8610 9221);
PAINT SKYBLUE (-8610 9221);
FORCEPROP 1 LAST MATERIAL CHIP
J 0
(-8610 9171);
DISPLAY 0.617021 (-8610 9171);
PAINT SKYBLUE (-8610 9171);
FORCEPROP 1 LAST LOCATION PR1301
J 0
(-8600 9371);
DISPLAY 0.617021 (-8600 9371);
PAINT AQUA (-8600 9371);
FORCEPROP 2 LAST CDS_LIB pure_quanta
J 0
(-8650 9228);
DISPLAY INVISIBLE (-8650 9228);
FORCEPROP 1 LAST PATH I9
J 0
(-8600 9450);
DISPLAY 0.978723 (-8600 9450);
PAINT WHITE (-8600 9450);
DISPLAY INVISIBLE (-8600 9450);
FORCEPROP 0 LAST $SEC 1
J 0
(-8600 9400);
DISPLAY 0.680851 (-8600 9400);
PAINT MONO (-8600 9400);
DISPLAY INVISIBLE (-8600 9400);
FORCEPROP 0 LAST CDS_SEC 1
J 0
(-8600 9400);
DISPLAY 1.021277 (-8600 9400);
DISPLAY INVISIBLE (-8600 9400);
FORCEPROP 1 LASTPIN (-8650 9375) $PN 1
J 0
(-8645 9299);
DISPLAY 0.808511 (-8645 9299);
PAINT WHITE (-8645 9299);
DISPLAY INVISIBLE (-8645 9299);
FORCEPROP 1 LASTPIN (-8650 9175) $PN 2
J 0
(-8645 9147);
DISPLAY 0.808511 (-8645 9147);
PAINT WHITE (-8645 9147);
DISPLAY INVISIBLE (-8645 9147);
FORCEADD DNS..2
(-9575 10050);
PAINT RED (-9575 10050);
FORCEPROP 2 LAST CDS_LIB mstr_misc
J 0
(-9575 10050);
PAINT MONO (-9575 10050);
DISPLAY INVISIBLE (-9575 10050);
FORCEPROP 1 LAST COMMENT_BODY TRUE
R 1
J 0
(-9500 9825);
DISPLAY 0.872340 (-9500 9825);
PAINT GREEN (-9500 9825);
DISPLAY INVISIBLE (-9500 9825);
FORCEADD DNS..2
(-9250 9650);
PAINT RED (-9250 9650);
FORCEPROP 2 LAST CDS_LIB mstr_misc
J 0
(-9250 9650);
DISPLAY INVISIBLE (-9250 9650);
FORCEPROP 1 LAST COMMENT_BODY TRUE
R 1
J 0
(-9175 9425);
DISPLAY 0.872340 (-9175 9425);
PAINT GREEN (-9175 9425);
DISPLAY INVISIBLE (-9175 9425);
FORCEADD DNS..2
(-2000 8750);
PAINT RED (-2000 8750);
FORCEPROP 2 LAST CDS_LIB mstr_misc
J 0
(-2000 8750);
DISPLAY INVISIBLE (-2000 8750);
FORCEPROP 1 LAST COMMENT_BODY TRUE
R 1
J 0
(-1925 8525);
DISPLAY 0.872340 (-1925 8525);
PAINT GREEN (-1925 8525);
DISPLAY INVISIBLE (-1925 8525);
FORCEADD QUANTA_TITLE_BLOCK_C..1
(-1250 6800);
FORCEPROP 0 LAST CDS_CON_LAST_MODIFIED Fri Aug 25 14:04:52 2023
J 0
(-3135 6815);
DISPLAY INVISIBLE (-3135 6815);
FORCEPROP 1 LAST CUSTOM_TXT_CDS <CON_LAST_MODIFIED>
J 0
(-3135 6815);
DISPLAY 0.978723 (-3135 6815);
FORCEPROP 2 LAST CUSTOM_TXT_CDS <XR_PAGE_TITLE>
J 0
(-9140 12050);
DISPLAY 0.638298 (-9140 12050);
PAINT PINK (-9140 12050);
DISPLAY INVISIBLE (-9140 12050);
FORCEPROP 1 LAST CUSTOM_TXT_CDS <NAME_2>
J 0
(-4425 6850);
FORCEPROP 1 LAST CUSTOM_TXT_CDS <NAME_1>
J 0
(-4425 6975);
FORCEPROP 1 LAST CUSTOM_TXT_CDS <Q_NUMBER>
J 0
(-2653 6903);
DISPLAY 1.212766 (-2653 6903);
FORCEPROP 1 LAST CUSTOM_TXT_CDS <Q_PROJ>
J 0
(-3632 6902);
DISPLAY 1.212766 (-3632 6902);
FORCEPROP 1 LAST CUSTOM_TXT_CDS <Q_REV>
J 0
(-1434 6903);
DISPLAY 1.212766 (-1434 6903);
FORCEPROP 1 LAST CUSTOM_TXT_CDS <CON_PAGE_NUM> OF <CON_TOTAL_PAGES>
J 0
(-1696 6818);
DISPLAY 0.978723 (-1696 6818);
FORCEPROP 1 LAST Q_TITLE PVNN_MAIN_CPU0
J 0
(-10550 6850);
DISPLAY 2.446809 (-10550 6850);
PAINT GREEN (-10550 6850);
FORCEPROP 1 LAST Q_DEPT 
J 1
(-5013 6849);
DISPLAY 1.957447 (-5013 6849);
PAINT GREEN (-5013 6849);
FORCEPROP 2 LAST CDS_XR_PAGE_TITLE CR-282 : @S9S_MB_2U_LIB.S9S_MB_2U(SCH_1):PAGE282
J 0
(-9140 12050);
DISPLAY 0.638298 (-9140 12050);
PAINT PINK (-9140 12050);
DISPLAY INVISIBLE (-9140 12050);
FORCEPROP 1 LAST COMMENT_BODY TRUE
J 0
(-1238 6787);
DISPLAY 0.978723 (-1238 6787);
PAINT GREEN (-1238 6787);
DISPLAY INVISIBLE (-1238 6787);
FORCEPROP 2 LAST PAGE_BORDER TRUE
J 0
(-9140 12050);
DISPLAY 0.638298 (-9140 12050);
PAINT PINK (-9140 12050);
DISPLAY INVISIBLE (-9140 12050);
FORCEPROP 1 LAST CDS_LMAN_SYM_OUTLINE -9475,6775,100,-125
J 0
(-1250 6800);
DISPLAY 0.468085 (-1250 6800);
PAINT GREEN (-1250 6800);
DISPLAY INVISIBLE (-1250 6800);
FORCEPROP 2 LAST CDS_LIB pure_quanta
J 0
(-1250 6800);
DISPLAY INVISIBLE (-1250 6800);
WIRE 16 -1 (-10350 10125)(-10350 10050);
WIRE 16 -1 (-8225 9450)(-8225 9500);
WIRE 16 -1 (-9125 10825)(-9125 11050);
WIRE 16 -1 (-8800 10825)(-9125 10825);
WIRE 16 -1 (-5425 11000)(-5425 11100);
WIRE 16 -1 (-1525 8750)(-1525 8800);
WIRE 16 -1 (-1975 8750)(-1525 8750);
WIRE 16 -1 (-1525 9850)(-1525 10050);
WIRE 16 -1 (-1525 9850)(-1525 9000);
WIRE 16 -1 (-1525 9850)(-1900 9850);
WIRE 16 -1 (-8225 8625)(-8225 8425);
WIRE 16 -1 (-9125 9575)(-9125 9500);
WIRE 16 -1 (-9225 9500)(-9125 9500);
WIRE 16 -1 (-8650 9175)(-8650 9025);
WIRE 16 -1 (-8800 10350)(-8800 10275);
WIRE 16 -1 (-8800 10350)(-8350 10350);
WIRE 16 -1 (-8800 10475)(-8800 10350);
WIRE 16 -1 (-7825 8575)(-7825 8425);
WIRE 16 -1 (-6450 8300)(-6450 8375);
WIRE 16 -1 (-1550 8375)(-1550 8075);
WIRE 16 -1 (-2725 8375)(-1550 8375);
WIRE 16 -1 (-6300 8800)(-6300 9050);
WIRE 16 -1 (-4350 10350)(-4350 10275);
WIRE 16 -1 (-1900 9425)(-1900 9325);
WIRE 16 -1 (-2300 9425)(-1900 9425);
WIRE 16 -1 (-1900 9425)(-1900 9550);
WIRE 16 -1 (-9225 9575)(-9225 9500);
WIRE 16 -1 (-5825 8575)(-5825 8375);
WIRE 16 -1 (-5375 8375)(-5825 8375);
WIRE 16 -1 (-6450 8375)(-5825 8375);
WIRE 16 -1 (-6450 9000)(-6450 8375);
WIRE 16 -1 (-6450 9000)(-6500 9000);
WIRE 16 -1 (-2725 8600)(-2725 8375);
WIRE 16 -1 (-5175 8375)(-4600 8375);
WIRE 16 -1 (-4600 8375)(-2725 8375);
WIRE 16 -1 (-4600 8575)(-4600 8375);
WIRE 16 -1 (-5325 9400)(-6500 9400);
WIRE 16 -1 (-5325 9400)(-5325 9000);
WIRE 16 -1 (-5325 9000)(-4600 9000);
FORCEPROP 2 LAST SIG_NAME PVNN_MAIN_CPU0_FB
J 0
(-4710 9010);
DISPLAY 0.617021 (-4710 9010);
WIRE 16 -1 (-4600 8775)(-4600 9000);
WIRE 16 -1 (-4600 9000)(-3900 9000);
WIRE 16 -1 (-3525 9000)(-3900 9000);
WIRE 16 -1 (-3900 8650)(-3900 9000);
WIRE 16 -1 (-3525 8650)(-3900 8650);
WIRE 16 -1 (-5175 9900)(-5175 9850);
WIRE 16 -1 (-4575 9850)(-5175 9850);
WIRE 16 -1 (-6500 9850)(-6350 9850);
WIRE 16 -1 (-6350 9850)(-5175 9850);
FORCEPROP 2 LAST SIG_NAME SW_PVNN_MAIN_CPU0_SW
J 0
(-6285 9860);
DISPLAY 0.617021 (-6285 9860);
WIRE 16 -1 (-6350 9900)(-6350 9850);
WIRE 16 -1 (-6500 9900)(-6350 9900);
WIRE 16 -1 (-3425 9850)(-4375 9850);
WIRE 16 -1 (-3425 9750)(-3425 9850);
WIRE 16 -1 (-3050 9850)(-3425 9850);
WIRE 16 -1 (-3050 9750)(-3050 9850);
WIRE 16 -1 (-2675 9850)(-3050 9850);
WIRE 16 -1 (-2675 9750)(-2675 9850);
WIRE 16 -1 (-2300 9850)(-2675 9850);
WIRE 16 -1 (-2300 9750)(-2300 9850);
WIRE 16 -1 (-1900 9850)(-2300 9850);
WIRE 16 -1 (-1900 9750)(-1900 9850);
WIRE 16 -1 (-1975 9000)(-1525 9000);
WIRE 16 -1 (-3425 9550)(-3425 9425);
WIRE 16 -1 (-3425 9425)(-3050 9425);
WIRE 16 -1 (-3050 9550)(-3050 9425);
WIRE 16 -1 (-3050 9425)(-2675 9425);
WIRE 16 -1 (-2675 9550)(-2675 9425);
WIRE 16 -1 (-2675 9425)(-2300 9425);
WIRE 16 -1 (-2300 9425)(-2300 9550);
WIRE 16 -1 (-2450 8750)(-2175 8750);
WIRE 16 -1 (-2450 9000)(-2450 8750);
WIRE 16 -1 (-2450 9000)(-2175 9000);
WIRE 16 -1 (-2725 9000)(-2725 8800);
WIRE 16 -1 (-2725 9000)(-2450 9000);
WIRE 16 -1 (-3000 9000)(-3325 9000);
WIRE 16 -1 (-2725 9000)(-3000 9000);
FORCEPROP 2 LAST SIG_NAME PVNN_MAIN_CPU0_FB_RC
J 0
(-3060 9010);
DISPLAY 0.617021 (-3060 9010);
WIRE 16 -1 (-3000 8650)(-3000 9000);
WIRE 16 -1 (-3325 8650)(-3000 8650);
WIRE 16 2175 (-3675 11600)(-1700 11600);
WIRE 16 2175 (-1700 12625)(-1700 11600);
WIRE 16 2175 (-3675 12625)(-3675 11600);
WIRE 16 2175 (-3675 12625)(-1700 12625);
WIRE 16 -1 (-4350 10550)(-4350 10625);
WIRE 16 -1 (-3625 10625)(-4350 10625);
WIRE 16 -1 (-4975 10625)(-4350 10625);
FORCEPROP 2 LAST SIG_NAME PWRGD_PVNN_MAIN_CPU0
J 0
(-4235 10635);
DISPLAY 0.617021 (-4235 10635);
WIRE 16 -1 (-5175 10150)(-5175 10100);
WIRE 16 -1 (-5350 10150)(-5175 10150);
FORCEPROP 2 LAST SIG_NAME SW_PVNN_MAIN_CPU0_BST_R
J 0
(-5310 10160);
DISPLAY 0.617021 (-5310 10160);
WIRE 16 -1 (-5550 10150)(-6500 10150);
FORCEPROP 2 LAST SIG_NAME SW_PVNN_MAIN_CPU0_BST
J 0
(-6285 10160);
DISPLAY 0.617021 (-6285 10160);
WIRE 16 -1 (-5175 10625)(-5425 10625);
WIRE 16 -1 (-5425 10800)(-5425 10625);
WIRE 16 -1 (-6350 10625)(-5425 10625);
WIRE 16 -1 (-6350 10350)(-6350 10625);
FORCEPROP 2 LAST SIG_NAME PWRGD_PVNN_MAIN_CPU0_R
J 0
(-6285 10635);
DISPLAY 0.617021 (-6285 10635);
WIRE 16 -1 (-6350 10350)(-6500 10350);
WIRE 16 -1 (-5825 9150)(-5825 8775);
WIRE 16 -1 (-6500 9150)(-5825 9150);
FORCEPROP 2 LAST SIG_NAME PVNN_MAIN_CPU0_REF
J 0
(-6235 9160);
DISPLAY 0.617021 (-6235 9160);
WIRE 16 -1 (-6500 9250)(-6300 9250);
WIRE 16 -1 (-6300 9050)(-6300 9250);
WIRE 16 -1 (-6500 9050)(-6300 9050);
WIRE 16 -1 (-7300 10350)(-7350 10350);
WIRE 16 -1 (-7350 10350)(-7350 10825);
WIRE 16 -1 (-7800 10675)(-7800 10825);
WIRE 16 -1 (-7350 10825)(-7800 10825);
WIRE 16 -1 (-8350 10675)(-8350 10825);
WIRE 16 -1 (-7800 10825)(-8350 10825);
WIRE 16 -1 (-8350 10825)(-8800 10825);
WIRE 16 -1 (-8800 10675)(-8800 10825);
WIRE 16 -1 (-7450 9400)(-7300 9400);
WIRE 16 -1 (-7450 9125)(-7450 9400);
WIRE 16 -1 (-8225 9250)(-8225 9125);
WIRE 16 -1 (-8225 9125)(-7450 9125);
FORCEPROP 2 LAST SIG_NAME PVNN_MAIN_CPU0_VCC
J 0
(-8010 9135);
DISPLAY 0.617021 (-8010 9135);
WIRE 16 -1 (-8225 8825)(-8225 9125);
WIRE 16 -1 (-7825 9050)(-7300 9050);
WIRE 16 -1 (-7825 8775)(-7825 9050);
FORCEPROP 2 LAST SIG_NAME PVNN_MAIN_CPU0_CS
J 0
(-7985 9060);
DISPLAY 0.617021 (-7985 9060);
WIRE 16 -1 (-8350 10475)(-8350 10350);
WIRE 16 -1 (-8350 10350)(-7800 10350);
WIRE 16 -1 (-7800 10475)(-7800 10350);
WIRE 16 -1 (-8900 10050)(-9500 10050);
WIRE 16 -1 (-8900 9850)(-8900 10050);
WIRE 16 -1 (-7300 9850)(-8900 9850);
WIRE 16 -1 (-9125 9850)(-10100 9850);
WIRE 16 -1 (-8900 9850)(-9125 9850);
WIRE 16 -1 (-9125 9775)(-9125 9825);
WIRE 16 -1 (-9125 9825)(-9125 9850);
WIRE 16 -1 (-9225 9825)(-9125 9825);
WIRE 16 -1 (-9225 9775)(-9225 9825);
WIRE 16 -1 (-8650 9650)(-7300 9650);
FORCEPROP 2 LAST SIG_NAME PVNN_MAIN_CPU0_MODE
J 0
(-8035 9660);
DISPLAY 0.617021 (-8035 9660);
WIRE 16 -1 (-8650 9375)(-8650 9650);
WIRE 16 -1 (-10350 10050)(-9700 10050);
WIRE 16 2175 (-10225 7400)(-9125 7400);
WIRE 16 2175 (-9125 7875)(-9125 7400);
WIRE 16 2175 (-10225 7875)(-10225 7400);
WIRE 16 2175 (-10225 7875)(-9125 7875);
DOT 1 (-8225 9125);
DOT 1 (-9125 9825);
DOT 1 (-9125 9850);
DOT 1 (-8900 9850);
DOT 1 (-8800 10350);
DOT 1 (-8350 10350);
DOT 1 (-8800 10825);
DOT 1 (-8350 10825);
DOT 1 (-6450 8375);
DOT 1 (-5825 8375);
DOT 1 (-4600 8375);
DOT 1 (-2725 8375);
DOT 1 (-6300 9050);
DOT 1 (-6350 9850);
DOT 1 (-7800 10825);
DOT 1 (-5175 9850);
DOT 1 (-4600 9000);
DOT 1 (-5425 10625);
DOT 1 (-4350 10625);
DOT 1 (-3900 9000);
DOT 1 (-3425 9850);
DOT 1 (-3050 9425);
DOT 1 (-3000 9000);
DOT 1 (-2675 9425);
DOT 1 (-2725 9000);
DOT 1 (-2450 9000);
DOT 1 (-2300 9425);
DOT 1 (-3050 9850);
DOT 1 (-2675 9850);
DOT 1 (-2300 9850);
DOT 1 (-1900 9425);
DOT 1 (-1900 9850);
DOT 1 (-1525 9850);
FORCENOTE
1ST AL053317005
(-10150 7675) 0;
DISPLAY LEFT (-10150 7675);
DISPLAY 1.170213 (-10150 7675);
PAINT WHITE (-10150 7675);
FORCENOTE
IC TABLE
(-10150 7775) 0;
DISPLAY LEFT (-10150 7775);
DISPLAY 1.170213 (-10150 7775);
PAINT WHITE (-10150 7775);
FORCENOTE
3RD AL008626000
(-10150 7475) 0;
DISPLAY LEFT (-10150 7475);
DISPLAY 1.170213 (-10150 7475);
PAINT WHITE (-10150 7475);
FORCENOTE
2ND AL54L061000
(-10150 7575) 0;
DISPLAY LEFT (-10150 7575);
DISPLAY 1.170213 (-10150 7575);
PAINT WHITE (-10150 7575);
FORCENOTE
20220804 CHANGE IC TABLE
(-10175 7225) 0;
DISPLAY LEFT (-10175 7225);
DISPLAY 1.595745 (-10175 7225);
PAINT PINK (-10175 7225);
FORCENOTE
20220808 ADD CHANGE LIST
(-4525 8150) 0;
DISPLAY LEFT (-4525 8150);
DISPLAY 1.595745 (-4525 8150);
PAINT PINK (-4525 8150);
FORCENOTE
PC237 MAIN 680PF
(-3825 8050) 0;
DISPLAY LEFT (-3825 8050);
DISPLAY 1.276596 (-3825 8050);
PAINT PINK (-3825 8050);
FORCENOTE
3RD 680PF
(-3400 7850) 0;
DISPLAY LEFT (-3400 7850);
DISPLAY 1.276596 (-3400 7850);
PAINT PINK (-3400 7850);
FORCENOTE
2ND 470PF
(-3400 7950) 0;
DISPLAY LEFT (-3400 7950);
DISPLAY 1.276596 (-3400 7950);
PAINT PINK (-3400 7950);
FORCENOTE
PLACE AT CHIPSET SIDE
(-2300 8400) 0;
DISPLAY LEFT (-2300 8400);
DISPLAY 1.021277 (-2300 8400);
FORCENOTE
DCR=40M OHM
(-4675 9600) 0;
DISPLAY LEFT (-4675 9600);
DISPLAY 0.808511 (-4675 9600);
FORCENOTE
TDC=0.52A
(-3650 12100) 0;
DISPLAY LEFT (-3650 12100);
DISPLAY 1.170213 (-3650 12100);
PAINT RED (-3650 12100);
FORCENOTE
VOUT=1V
(-3650 12425) 0;
DISPLAY LEFT (-3650 12425);
DISPLAY 1.170213 (-3650 12425);
PAINT WHITE (-3650 12425);
FORCENOTE
MAX CURRENT=0.52A
(-3649 12011) 0;
DISPLAY LEFT (-3649 12011);
DISPLAY 1.170213 (-3649 12011);
PAINT RED (-3649 12011);
FORCENOTE
RIPPLE=+/-7MV
(-3650 12250) 0;
DISPLAY LEFT (-3650 12250);
DISPLAY 1.170213 (-3650 12250);
PAINT RED (-3650 12250);
FORCENOTE
DC TOLERANCE=+/-0.7%
(-3650 12325) 0;
DISPLAY LEFT (-3650 12325);
DISPLAY 1.276596 (-3650 12325);
PAINT WHITE (-3650 12325);
FORCENOTE
OCP(IMAX*130%)=1A
(-3649 11936) 0;
DISPLAY LEFT (-3649 11936);
DISPLAY 1.170213 (-3649 11936);
PAINT WHITE (-3649 11936);
FORCENOTE
CURRENT STEP=0.52A
(-3649 11861) 0;
DISPLAY LEFT (-3649 11861);
DISPLAY 1.170213 (-3649 11861);
PAINT RED (-3649 11861);
FORCENOTE
SLEW RATE=0.4A/US
(-3649 11786) 0;
DISPLAY LEFT (-3649 11786);
DISPLAY 1.170213 (-3649 11786);
PAINT RED (-3649 11786);
FORCENOTE
WORK FREQUENCY=600KHZ
(-3649 11716) 0;
DISPLAY LEFT (-3649 11716);
DISPLAY 1.170213 (-3649 11716);
PAINT WHITE (-3649 11716);
FORCENOTE
PDG REV 1.6
(-3650 11625) 0;
DISPLAY LEFT (-3650 11625);
DISPLAY 1.170213 (-3650 11625);
PAINT RED (-3650 11625);
FORCENOTE
TOTAL TOL=1.03VMAX/0.97VMIN 
(-3650 12175) 0;
DISPLAY LEFT (-3650 12175);
DISPLAY 1.276596 (-3650 12175);
PAINT RED (-3650 12175);
FORCENOTE
REMOTE SENSE
(-2300 8475) 0;
DISPLAY LEFT (-2300 8475);
DISPLAY 1.021277 (-2300 8475);
FORCENOTE
20220808 UPDATE PDG REV 1.6
(-3700 11475) 0;
DISPLAY LEFT (-3700 11475);
DISPLAY 1.595745 (-3700 11475);
FORCENOTE
UPDATE 20220531 ADD LOCAL SENSE
(-3050 9100) 0;
DISPLAY LEFT (-3050 9100);
DISPLAY 1.021277 (-3050 9100);
FORCENOTE
PVNN_MAIN_CPU0 SPECIFICATION
(-3650 12540) 0;
DISPLAY LEFT (-3650 12540);
DISPLAY 1.468085 (-3650 12540);
PAINT WHITE (-3650 12540);
FORCENOTE
PVNN_MAIN_CPU0
(-8150 11675) 0;
DISPLAY LEFT (-8150 11675);
DISPLAY 3.148936 (-8150 11675);
PAINT YELLOW (-8150 11675);
FORCENOTE
PCMC063T-4R7MN
(-4675 9750) 0;
DISPLAY LEFT (-4675 9750);
DISPLAY 0.808511 (-4675 9750);
FORCENOTE
6.5*6.9*3.0
(-4675 9700) 0;
DISPLAY LEFT (-4675 9700);
DISPLAY 0.808511 (-4675 9700);
FORCENOTE
ISAT=9A@100C
(-4675 9650) 0;
DISPLAY LEFT (-4675 9650);
DISPLAY 0.808511 (-4675 9650);
QUIT
